# Altium SchDoc records: 04-PCIe_JTAG.SchDoc
|HEADER=Protel for Windows - Schematic Capture Binary File Version 5.0|Weight=1193|MinorVersion=6
|RECORD=31|FontIdCount=9|Size1=10|FontName1=Times New Roman|Size2=8|FontName2=Arial|Size3=10|FontName3=Arial|Size4=12|Underline4=T|FontName4=Arial|Size5=11|FontName5=Arial|Size6=24|FontName6=Times New Roman|Size7=12|FontName7=Arial|Size8=7|FontName8=Arial|Size9=7|FontName9=Courier New|UseMBCS=T|IsBOC=T|HotSpotGridOn=T|HotSpotGridSize_Frac=40000|SheetStyle=12|SystemFont=3|BorderOn=T|SheetNumberSpaceSize=12|AreaColor=16317695|SnapGridOn=T|SnapGridSize=1|VisibleGridOn=T|VisibleGridSize=10|CustomX=2338|CustomX_Frac=58268|CustomY=1653|CustomY_Frac=54331|CustomXZones=8|CustomYZones=6|CustomMarginWidth=19|CustomMarginWidth_Frac=80000|ShowTemplateGraphics=T|TemplateFileName=C:\Users\<user>\Documents\Altium\AD20\Templates\Timecard.SchDot|Display_Unit=0
|RECORD=39|IsNotAccesible=T|OwnerPartId=-1|FileName=C:\Users\<user>\Documents\Altium\AD20\Templates\Timecard.SchDot
|RECORD=4|OwnerIndex=1|OwnerPartId=-1|Location.X=1594|Location.Y=39|Color=8388608|FontID=4|Text=timingcard.com|URL=http://timingcard.com
|RECORD=6|OwnerIndex=1|IndexInSheet=1|OwnerPartId=-1|LocationCount=2|X1=1680|Y1=35|X2=1576|Y2=35
|RECORD=4|OwnerIndex=1|IndexInSheet=2|OwnerPartId=-1|Location.X=1615|Location.Y=27|Justification=4|Color=16711680|FontID=5|Text==SheetNumber
|RECORD=4|OwnerIndex=1|IndexInSheet=3|OwnerPartId=-1|Location.X=1581|Location.X_Frac=42446|Location.Y=29|Location.Y_Frac=96838|Justification=3|FontID=2|Text=SHEET
|RECORD=4|OwnerIndex=1|IndexInSheet=4|OwnerPartId=-1|Location.X=1639|Location.X_Frac=42446|Location.Y=29|Location.Y_Frac=96838|Justification=3|FontID=2|Text=OF
|RECORD=6|OwnerIndex=1|IndexInSheet=5|OwnerPartId=-1|LineWidth=1|LocationCount=2|X1=1679|X1_Frac=42446|Y1=117|Y1_Frac=96838|X2=1576|Y2=118
|RECORD=4|OwnerIndex=1|IndexInSheet=6|OwnerPartId=-1|Location.X=1659|Location.Y=27|Justification=4|Color=16711680|FontID=5|Text==SheetTotal
|RECORD=30|OwnerIndex=1|IndexInSheet=7|OwnerPartId=-1|Location.X=1578|Location.Y=65|Corner.X=1673|Corner.X_Frac=88801|Corner.Y=115|KeepAspect=T|FileName=C:\Users\<user>\Desktop\Timecard Logo\TIMECARD.jpg
|RECORD=6|OwnerIndex=1|IndexInSheet=8|OwnerPartId=-1|LineWidth=1|LocationCount=2|X1=1576|X1_Frac=3162|Y1=117|Y1_Frac=42446|X2=1576|Y2=21
|RECORD=6|OwnerIndex=1|IndexInSheet=9|OwnerPartId=-1|LocationCount=2|X1=1680|Y1=51|X2=1576|Y2=51
|RECORD=4|OwnerIndex=1|IndexInSheet=10|OwnerPartId=-1|Location.X=1581|Location.X_Frac=42446|Location.Y=56|Location.Y_Frac=96838|Justification=3|FontID=2|Text=REV
|RECORD=4|OwnerIndex=1|IndexInSheet=11|OwnerPartId=-1|Location.X=1619|Location.Y=57|Justification=3|FontID=2|Text=DATE
|RECORD=6|OwnerIndex=1|IndexInSheet=12|OwnerPartId=-1|LocationCount=2|X1=1680|Y1=65|X2=1576|Y2=65
|RECORD=4|OwnerIndex=1|IndexInSheet=13|OwnerPartId=-1|Location.X=1605|Location.Y=58|Justification=4|Color=16711680|FontID=5|Text==ProjectRevision
|RECORD=4|OwnerIndex=1|IndexInSheet=14|OwnerPartId=-1|Location.X=1659|Location.Y=58|Justification=4|Color=16711680|FontID=5|Text==ProjectDate
|RECORD=41|IndexInSheet=1|OwnerPartId=-1|Location.X=21474|Location.X_Frac=83647|Location.Y=21464|Location.Y_Frac=83647|Color=8388608|FontID=1|IsHidden=T|Text=01910|Name=Customer
|RECORD=41|IndexInSheet=2|OwnerPartId=-1|Location.X=1000|Location.Y=10|Color=8388608|FontID=1|IsHidden=T|Text=*|Name=DocStatus
|RECORD=17|IndexInSheet=3|OwnerPartId=-1|Style=4|ShowNetName=T|Location.X=740|Location.Y=600|Orientation=3|Color=128|FontID=1|Text=GND
|RECORD=17|IndexInSheet=4|OwnerPartId=-1|Style=4|ShowNetName=T|Location.X=940|Location.Y=600|Orientation=3|Color=128|FontID=1|Text=GND
|RECORD=17|IndexInSheet=5|OwnerPartId=-1|ShowNetName=T|Location.X=670|Location.Y=970|Orientation=1|Color=128|FontID=1|Text=+12V_PCIE
|RECORD=17|IndexInSheet=6|OwnerPartId=-1|ShowNetName=T|Location.X=540|Location.Y=970|Orientation=1|Color=128|FontID=1|Text=+3.3V_PCIE
|RECORD=17|IndexInSheet=7|OwnerPartId=-1|ShowNetName=T|Location.X=1060|Location.Y=920|Orientation=1|Color=128|FontID=1|Text=+3.3V
|RECORD=17|IndexInSheet=8|OwnerPartId=-1|ShowNetName=T|Location.X=1030|Location.Y=940|Orientation=1|Color=128|FontID=1|Text=+3.3V_PCIE
|RECORD=17|IndexInSheet=9|OwnerPartId=-1|ShowNetName=T|Location.X=990|Location.Y=970|Orientation=1|Color=128|FontID=1|Text=+12V_PCIE
|RECORD=22|IndexInSheet=10|OwnerPartId=-1|Location.X=760|Location.Y=910|Color=255|Orientation=1|Symbol=Thin Cross|IsActive=T|SuppressAll=T
|RECORD=22|IndexInSheet=11|OwnerPartId=-1|Location.X=760|Location.Y=900|Color=255|Orientation=1|Symbol=Thin Cross|IsActive=T|SuppressAll=T
|RECORD=22|IndexInSheet=12|OwnerPartId=-1|Location.X=760|Location.Y=850|Color=255|Orientation=1|Symbol=Thin Cross|IsActive=T|SuppressAll=T
|RECORD=17|IndexInSheet=13|OwnerPartId=-1|ShowNetName=T|Location.X=540|Location.Y=810|Orientation=2|Color=255|FontID=1|Text=PCIE_RX0_P|IsCrossSheetConnector=T
|RECORD=41|OwnerIndex=29|OwnerPartId=-1|Location.X=473|Location.X_Frac=63845|Location.Y=810|Orientation=2|Justification=3|Color=8388608|FontID=1|Text=FPGA[4C]|Name=CrossRef|ReadOnlyState=3
|RECORD=17|IndexInSheet=14|OwnerPartId=-1|ShowNetName=T|Location.X=540|Location.Y=800|Orientation=2|Color=255|FontID=1|Text=PCIE_RX0_N|IsCrossSheetConnector=T
|RECORD=41|OwnerIndex=31|OwnerPartId=-1|Location.X=471|Location.X_Frac=94974|Location.Y=800|Orientation=2|Justification=3|Color=8388608|FontID=1|Text=FPGA[4C]|Name=CrossRef|ReadOnlyState=3
|RECORD=17|IndexInSheet=15|OwnerPartId=-1|ShowNetName=T|Location.X=540|Location.Y=760|Orientation=2|Color=255|FontID=1|Text=PCIE_RX1_P|IsCrossSheetConnector=T
|RECORD=41|OwnerIndex=33|OwnerPartId=-1|Location.X=473|Location.X_Frac=63845|Location.Y=760|Orientation=2|Justification=3|Color=8388608|FontID=1|Text=FPGA[5C]|Name=CrossRef|ReadOnlyState=3
|RECORD=17|IndexInSheet=16|OwnerPartId=-1|ShowNetName=T|Location.X=540|Location.Y=750|Orientation=2|Color=255|FontID=1|Text=PCIE_RX1_N|IsCrossSheetConnector=T
|RECORD=41|OwnerIndex=35|OwnerPartId=-1|Location.X=471|Location.X_Frac=94974|Location.Y=750|Orientation=2|Justification=3|Color=8388608|FontID=1|Text=FPGA[5C]|Name=CrossRef|ReadOnlyState=3
|RECORD=17|IndexInSheet=17|OwnerPartId=-1|ShowNetName=T|Location.X=540|Location.Y=720|Orientation=2|Color=255|FontID=1|Text=PCIE_RX2_P|IsCrossSheetConnector=T
|RECORD=41|OwnerIndex=37|OwnerPartId=-1|Location.X=473|Location.X_Frac=63845|Location.Y=720|Orientation=2|Justification=3|Color=8388608|FontID=1|Text=FPGA[5C]|Name=CrossRef|ReadOnlyState=3
|RECORD=17|IndexInSheet=18|OwnerPartId=-1|ShowNetName=T|Location.X=540|Location.Y=710|Orientation=2|Color=255|FontID=1|Text=PCIE_RX2_N|IsCrossSheetConnector=T
|RECORD=41|OwnerIndex=39|OwnerPartId=-1|Location.X=471|Location.X_Frac=94974|Location.Y=710|Orientation=2|Justification=3|Color=8388608|FontID=1|Text=FPGA[5C]|Name=CrossRef|ReadOnlyState=3
|RECORD=17|IndexInSheet=19|OwnerPartId=-1|ShowNetName=T|Location.X=540|Location.Y=680|Orientation=2|Color=255|FontID=1|Text=PCIE_RX3_P|IsCrossSheetConnector=T
|RECORD=41|OwnerIndex=41|OwnerPartId=-1|Location.X=473|Location.X_Frac=63845|Location.Y=680|Orientation=2|Justification=3|Color=8388608|FontID=1|Text=FPGA[4C]|Name=CrossRef|ReadOnlyState=3
|RECORD=17|IndexInSheet=20|OwnerPartId=-1|ShowNetName=T|Location.X=540|Location.Y=670|Orientation=2|Color=255|FontID=1|Text=PCIE_RX3_N|IsCrossSheetConnector=T
|RECORD=41|OwnerIndex=43|OwnerPartId=-1|Location.X=471|Location.X_Frac=94974|Location.Y=670|Orientation=2|Justification=3|Color=8388608|FontID=1|Text=FPGA[4C]|Name=CrossRef|ReadOnlyState=3
|RECORD=17|IndexInSheet=21|OwnerPartId=-1|ShowNetName=T|Location.X=1190|Location.Y=850|Color=255|FontID=1|Text=PCIE_PERST|IsCrossSheetConnector=T
|RECORD=41|OwnerIndex=45|OwnerPartId=-1|Location.X=1256|Location.X_Frac=95678|Location.Y=850|Justification=3|Color=8388608|FontID=1|Text=FPGA[2C], GPS_IMU_SENSORS[4C]|Name=CrossRef|ReadOnlyState=3
|RECORD=17|IndexInSheet=22|OwnerPartId=-1|ShowNetName=T|Location.X=1190|Location.Y=820|Color=255|FontID=1|Text=PCIE_CLK_P|IsCrossSheetConnector=T
|RECORD=41|OwnerIndex=47|OwnerPartId=-1|Location.X=1257|Location.X_Frac=36242|Location.Y=820|Justification=3|Color=8388608|FontID=1|Text=FPGA[5C]|Name=CrossRef|ReadOnlyState=3
|RECORD=17|IndexInSheet=23|OwnerPartId=-1|ShowNetName=T|Location.X=1190|Location.Y=810|Color=255|FontID=1|Text=PCIE_CLK_N|IsCrossSheetConnector=T
|RECORD=41|OwnerIndex=49|OwnerPartId=-1|Location.X=1259|Location.X_Frac=5114|Location.Y=810|Justification=3|Color=8388608|FontID=1|Text=FPGA[5C]|Name=CrossRef|ReadOnlyState=3
|RECORD=17|IndexInSheet=24|OwnerPartId=-1|ShowNetName=T|Location.X=1190|Location.Y=790|Color=255|FontID=1|Text=PCIE_TX0_P|IsCrossSheetConnector=T
|RECORD=41|OwnerIndex=51|OwnerPartId=-1|Location.X=1255|Location.X_Frac=85450|Location.Y=790|Justification=3|Color=8388608|FontID=1|Text=FPGA[4C]|Name=CrossRef|ReadOnlyState=3
|RECORD=17|IndexInSheet=25|OwnerPartId=-1|ShowNetName=T|Location.X=1190|Location.Y=780|Color=255|FontID=1|Text=PCIE_TX0_N|IsCrossSheetConnector=T
|RECORD=41|OwnerIndex=53|OwnerPartId=-1|Location.X=1257|Location.X_Frac=54320|Location.Y=780|Justification=3|Color=8388608|FontID=1|Text=FPGA[4C]|Name=CrossRef|ReadOnlyState=3
|RECORD=17|IndexInSheet=26|OwnerPartId=-1|ShowNetName=T|Location.X=1190|Location.Y=740|Color=255|FontID=1|Text=PCIE_TX1_P|IsCrossSheetConnector=T
|RECORD=41|OwnerIndex=55|OwnerPartId=-1|Location.X=1255|Location.X_Frac=85450|Location.Y=740|Justification=3|Color=8388608|FontID=1|Text=FPGA[5C]|Name=CrossRef|ReadOnlyState=3
|RECORD=17|IndexInSheet=27|OwnerPartId=-1|ShowNetName=T|Location.X=1190|Location.Y=730|Color=255|FontID=1|Text=PCIE_TX1_N|IsCrossSheetConnector=T
|RECORD=41|OwnerIndex=57|OwnerPartId=-1|Location.X=1257|Location.X_Frac=54320|Location.Y=730|Justification=3|Color=8388608|FontID=1|Text=FPGA[5C]|Name=CrossRef|ReadOnlyState=3
|RECORD=17|IndexInSheet=28|OwnerPartId=-1|ShowNetName=T|Location.X=1190|Location.Y=700|Color=255|FontID=1|Text=PCIE_TX2_P|IsCrossSheetConnector=T
|RECORD=41|OwnerIndex=59|OwnerPartId=-1|Location.X=1255|Location.X_Frac=85450|Location.Y=700|Justification=3|Color=8388608|FontID=1|Text=FPGA[5C]|Name=CrossRef|ReadOnlyState=3
|RECORD=17|IndexInSheet=29|OwnerPartId=-1|ShowNetName=T|Location.X=1190|Location.Y=690|Color=255|FontID=1|Text=PCIE_TX2_N|IsCrossSheetConnector=T
|RECORD=41|OwnerIndex=61|OwnerPartId=-1|Location.X=1257|Location.X_Frac=54320|Location.Y=690|Justification=3|Color=8388608|FontID=1|Text=FPGA[5C]|Name=CrossRef|ReadOnlyState=3
|RECORD=17|IndexInSheet=30|OwnerPartId=-1|ShowNetName=T|Location.X=1190|Location.Y=660|Color=255|FontID=1|Text=PCIE_TX3_P|IsCrossSheetConnector=T
|RECORD=41|OwnerIndex=63|OwnerPartId=-1|Location.X=1255|Location.X_Frac=85450|Location.Y=660|Justification=3|Color=8388608|FontID=1|Text=FPGA[4C]|Name=CrossRef|ReadOnlyState=3
|RECORD=17|IndexInSheet=31|OwnerPartId=-1|ShowNetName=T|Location.X=1190|Location.Y=650|Color=255|FontID=1|Text=PCIE_TX3_N|IsCrossSheetConnector=T
|RECORD=41|OwnerIndex=65|OwnerPartId=-1|Location.X=1257|Location.X_Frac=54320|Location.Y=650|Justification=3|Color=8388608|FontID=1|Text=FPGA[4C]|Name=CrossRef|ReadOnlyState=3
|RECORD=4|IndexInSheet=32|OwnerPartId=-1|Location.X=800|Location.Y=1010|Color=8388608|FontID=6|Text=PCIe Connector
|RECORD=1|LibReference=RES_0603_4.7K|ComponentDescription=RES, 4.7K, 1%, 1/10W, TF, 0603|PartCount=2|DisplayModeCount=1|IndexInSheet=33|OwnerPartId=-1|Location.X=1060|Location.Y=860|Orientation=1|CurrentPartId=1|LibraryPath=*|SourceLibraryName=Resistors.IntLib|TargetFileName=*|AreaColor=11599871|Color=128|PartIDLocked=F|DesignItemId=RES_0603_4.7K|AllPinCount=2
|RECORD=41|OwnerIndex=68|OwnerPartId=-1|Location.X=1056|Location.Y=912|Color=8388608|FontID=7|IsHidden=T|Text=7/25/2013|Name=ModifyDate
|RECORD=41|OwnerIndex=68|IndexInSheet=1|OwnerPartId=-1|Location.X=1056|Location.Y=912|Color=8388608|FontID=7|IsHidden=T|Text=ERJ-3EKF4701V|Name=MFG PART NUM
|RECORD=41|OwnerIndex=68|IndexInSheet=2|OwnerPartId=-1|Location.X=1056|Location.Y=912|Color=8388608|FontID=7|IsHidden=T|Text=PANASONIC|Name=MFG NAME
|RECORD=41|OwnerIndex=68|IndexInSheet=3|OwnerPartId=-1|Location.X=1056|Location.Y=912|Color=8388608|FontID=7|IsHidden=T|Text=RES|Name=CATEGORY
|RECORD=41|OwnerIndex=68|IndexInSheet=4|OwnerPartId=-1|Location.X=1056|Location.Y=912|Color=8388608|FontID=7|IsHidden=T|Text=7/26/2013|Name=Date
|RECORD=41|OwnerIndex=68|IndexInSheet=5|OwnerPartId=-1|Location.X=1056|Location.Y=912|Color=8388608|FontID=7|IsHidden=T|Text=1%|Name=P1
|RECORD=41|OwnerIndex=68|IndexInSheet=6|OwnerPartId=-1|Location.X=1056|Location.Y=912|Color=8388608|FontID=7|IsHidden=T|Text=TF|Name=P3
|RECORD=41|OwnerIndex=68|IndexInSheet=7|OwnerPartId=-1|Location.X=1056|Location.Y=912|Color=8388608|FontID=7|IsHidden=T|Text=1/10W|Name=P2
|RECORD=41|OwnerIndex=68|IndexInSheet=8|OwnerPartId=-1|Location.X=1056|Location.Y=912|Color=8388608|FontID=7|IsHidden=T|Text=125C|Name=MAXTEMP
|RECORD=41|OwnerIndex=68|IndexInSheet=9|OwnerPartId=-1|Location.X=1056|Location.Y=912|Color=8388608|FontID=7|IsHidden=T|Text=-55C|Name=MINTEMP
|RECORD=41|OwnerIndex=68|IndexInSheet=10|OwnerPartId=-1|Location.X=1056|Location.Y=912|Color=8388608|FontID=7|IsHidden=T|Text=100PPM|Name=OTHER
|RECORD=41|OwnerIndex=68|IndexInSheet=11|OwnerPartId=-1|Location.X=1056|Location.Y=912|Color=8388608|FontID=7|IsHidden=T|Text=0603|Name=SIZE
|RECORD=41|OwnerIndex=68|IndexInSheet=12|OwnerPartId=-1|Location.X=1056|Location.Y=912|Color=8388608|FontID=7|IsHidden=T|Text=GENERIC|Name=SUB
|RECORD=41|OwnerIndex=68|IndexInSheet=13|OwnerPartId=-1|Location.X=1056|Location.Y=912|Color=8388608|FontID=7|IsHidden=T|Text=Digi-Key|Name=Supplier 1|ReadOnlyState=3
|RECORD=41|OwnerIndex=68|IndexInSheet=14|OwnerPartId=-1|Location.X=1056|Location.Y=912|Color=8388608|FontID=7|IsHidden=T|Text=P4.70KHCT-ND|Name=Supplier Part Number 1|ReadOnlyState=3
|RECORD=41|OwnerIndex=68|IndexInSheet=15|OwnerPartId=-1|Location.X=1056|Location.Y=912|Color=8388608|FontID=1|IsHidden=T|Text=*|Name=SHEETPART
|RECORD=41|OwnerIndex=68|IndexInSheet=16|OwnerPartId=-1|Location.X=1056|Location.Y=912|Color=8388608|FontID=1|IsHidden=T|Text=RES, 4.7K, 1%, 1/10W, TF, 0603|Name=DESC
|RECORD=41|OwnerIndex=68|IndexInSheet=17|OwnerPartId=-1|Location.X=1064|Location.Y=875|Color=8388608|FontID=7|Text=4.7K|Name=VALUE
|RECORD=2|OwnerIndex=68|OwnerPartId=1|FormalType=1|Electrical=4|PinConglomerate=35|PinLength=10|Location.X=1060|Location.Y=870|Name=1|Designator=1|PinPropagationDelay=0.000000E+000
|RECORD=2|OwnerIndex=68|OwnerPartId=1|FormalType=1|Electrical=4|PinConglomerate=33|PinLength=10|Location.X=1060|Location.Y=900|Name=2|Designator=2|PinPropagationDelay=0.000000E+000
|RECORD=6|OwnerIndex=68|IsNotAccesible=T|IndexInSheet=20|OwnerPartId=1|LineWidth=1|Color=16711680|LocationCount=7|X1=1060|Y1=900|X2=1057|Y2=897|X3=1063|Y3=891|X4=1057|Y4=885|X5=1063|Y5=879|X6=1057|Y6=873|X7=1060|Y7=870
|RECORD=41|OwnerIndex=68|IndexInSheet=21|OwnerPartId=-1|Location.X=1056|Location.Y=912|Color=8388608|FontID=1|IsHidden=T|Text=<VELENTIUM>|Name=VELENTIUM PART NUM
|RECORD=34|OwnerIndex=68|IndexInSheet=-1|OwnerPartId=-1|Location.X=1064|Location.Y=887|Color=8388608|FontID=1|Text=R22|Name=Designator|ReadOnlyState=1
|RECORD=41|OwnerIndex=68|IndexInSheet=-1|OwnerPartId=-1|Location.X=1056|Location.Y=912|Color=8388608|FontID=1|IsHidden=T|Text==MFG PART NUM|Name=Comment
|RECORD=44|OwnerIndex=68
|RECORD=45|OwnerIndex=95|IndexInSheet=-1|Description=Chip Resistor, 0603, 2-Leads, Body 1.57x0.85mm, IPC Medium Density|UseComponentLibrary=T|ModelName=RESC1608X50N|ModelType=PCBLIB|DatafileCount=1|ModelDatafileEntity0=RESC1608X50N|ModelDatafileKind0=PCBLib|IsCurrent=T|DatalinksLocked=T|DatabaseDatalinksLocked=T|IntegratedModel=T|DatabaseModel=T
|RECORD=46|OwnerIndex=96
|RECORD=48|OwnerIndex=96
|RECORD=1|LibReference=CAP_0402_0.1UF_50V|ComponentDescription=CAP, CER, 0.1UF, 50V, 10%, X7R, AEC-Q200, 0402|PartCount=2|DisplayModeCount=1|IndexInSheet=34|OwnerPartId=-1|Location.X=1130|Location.Y=630|Orientation=1|CurrentPartId=1|LibraryPath=*|SourceLibraryName=Capacitors.IntLib|TargetFileName=*|AreaColor=11599871|Color=128|PartIDLocked=F|DesignItemId=CAP_0402_0.1UF_50V|AllPinCount=2
|RECORD=41|OwnerIndex=99|OwnerPartId=-1|Location.X=1078|Location.Y=656|Color=8388608|FontID=7|IsHidden=T|Text=CAP, CER|Name=CATEGORY
|RECORD=41|OwnerIndex=99|IndexInSheet=1|OwnerPartId=-1|Location.X=1078|Location.Y=656|Color=8388608|FontID=7|IsHidden=T|Text=TDK|Name=MFG NAME
|RECORD=41|OwnerIndex=99|IndexInSheet=2|OwnerPartId=-1|Location.X=1078|Location.Y=656|Color=8388608|FontID=7|IsHidden=T|Text=CGA2B3X7R1H104K050BB|Name=MFG PART NUM
|RECORD=41|OwnerIndex=99|IndexInSheet=3|OwnerPartId=-1|Location.X=1078|Location.Y=656|Color=8388608|FontID=7|IsHidden=T|Text=10/23/2013|Name=MODIFY DATE
|RECORD=41|OwnerIndex=99|IndexInSheet=4|OwnerPartId=-1|Location.X=1078|Location.Y=656|Color=8388608|FontID=7|IsHidden=T|Name=Date
|RECORD=41|OwnerIndex=99|IndexInSheet=5|OwnerPartId=-1|Location.X=1078|Location.Y=656|Color=8388608|FontID=7|IsHidden=T|Text=*|Name=SHEETPART
|RECORD=41|OwnerIndex=99|IndexInSheet=6|OwnerPartId=-1|Location.X=1078|Location.Y=656|Color=8388608|FontID=7|IsHidden=T|Text=10%|Name=P1
|RECORD=41|OwnerIndex=99|IndexInSheet=7|OwnerPartId=-1|Location.X=1078|Location.Y=656|Color=8388608|FontID=7|IsHidden=T|Text=125C|Name=MAXTEMP
|RECORD=41|OwnerIndex=99|IndexInSheet=8|OwnerPartId=-1|Location.X=1078|Location.Y=656|Color=8388608|FontID=7|IsHidden=T|Text=-55C|Name=MINTEMP
|RECORD=41|OwnerIndex=99|IndexInSheet=9|OwnerPartId=-1|Location.X=1078|Location.Y=656|Color=8388608|FontID=7|IsHidden=T|Text=AEC-Q200|Name=OTHER
|RECORD=41|OwnerIndex=99|IndexInSheet=10|OwnerPartId=-1|Location.X=1078|Location.Y=656|Color=8388608|FontID=7|IsHidden=T|Text=50V|Name=P2
|RECORD=41|OwnerIndex=99|IndexInSheet=11|OwnerPartId=-1|Location.X=1078|Location.Y=656|Color=8388608|FontID=7|IsHidden=T|Text=X7R|Name=P3
|RECORD=41|OwnerIndex=99|IndexInSheet=12|OwnerPartId=-1|Location.X=1078|Location.Y=656|Color=8388608|FontID=7|IsHidden=T|Text=0402|Name=Size
|RECORD=41|OwnerIndex=99|IndexInSheet=13|OwnerPartId=-1|Location.X=1078|Location.Y=656|Color=8388608|FontID=7|IsHidden=T|Name=SUB
|RECORD=41|OwnerIndex=99|IndexInSheet=14|OwnerPartId=-1|Location.X=1078|Location.Y=656|Color=8388608|FontID=1|IsHidden=T|Text=CAP, CER, 0.1UF, 50V, 10%, X7R, AEC-Q200, 0402|Name=DESC
|RECORD=41|OwnerIndex=99|IndexInSheet=15|OwnerPartId=-1|Location.X=1078|Location.Y=656|Color=8388608|FontID=1|IsHidden=T|Text=Digi-Key|Name=Supplier 1|ReadOnlyState=3
|RECORD=41|OwnerIndex=99|IndexInSheet=16|OwnerPartId=-1|Location.X=1078|Location.Y=656|Color=8388608|FontID=1|IsHidden=T|Text=445-6899-1-ND|Name=Supplier Part Number 1|ReadOnlyState=3
|RECORD=41|OwnerIndex=99|IndexInSheet=17|OwnerPartId=-1|Location.X=1101|Location.Y=638|Color=8388608|FontID=7|Text=0.1UF|Name=VALUE
|RECORD=2|OwnerIndex=99|OwnerPartId=1|FormalType=1|Electrical=4|PinConglomerate=32|PinLength=10|Location.X=1100|Location.Y=650|Name=2|Designator=2|SwapIdPin=2|SwapIDPart=1|PinPropagationDelay=0.000000E+000
|RECORD=2|OwnerIndex=99|OwnerPartId=1|FormalType=1|Electrical=4|PinConglomerate=34|PinLength=10|Location.X=1090|Location.Y=650|Name=1|Designator=1|SwapIdPin=1|SwapIDPart=1|PinPropagationDelay=0.000000E+000
|RECORD=13|OwnerIndex=99|IsNotAccesible=T|IndexInSheet=20|OwnerPartId=1|Location.X=1097|Location.X_Frac=50000|Location.Y=650|Corner.X=1100|Corner.Y=650|LineWidth=1|Color=16711680
|RECORD=13|OwnerIndex=99|IsNotAccesible=T|IndexInSheet=21|OwnerPartId=1|Location.X=1090|Location.Y=650|Corner.X=1092|Corner.X_Frac=50000|Corner.Y=650|LineWidth=1|Color=16711680
|RECORD=13|OwnerIndex=99|IsNotAccesible=T|IndexInSheet=22|OwnerPartId=1|Location.X=1097|Location.X_Frac=50000|Location.Y=655|Corner.X=1097|Corner.X_Frac=50000|Corner.Y=645|LineWidth=1|Color=16711680
|RECORD=13|OwnerIndex=99|IsNotAccesible=T|IndexInSheet=23|OwnerPartId=1|Location.X=1092|Location.X_Frac=50000|Location.Y=655|Corner.X=1092|Corner.X_Frac=50000|Corner.Y=645|LineWidth=1|Color=16711680
|RECORD=41|OwnerIndex=99|IndexInSheet=24|OwnerPartId=-1|Location.X=1078|Location.Y=656|Color=8388608|FontID=1|IsHidden=T|Text=<VALENTIUM>|Name=VALENTIUM PART NUM
|RECORD=34|OwnerIndex=99|IndexInSheet=-1|OwnerPartId=-1|Location.X=1070|Location.Y=636|Color=8388608|FontID=1|Text=C53|Name=Designator|ReadOnlyState=1
|RECORD=41|OwnerIndex=99|IndexInSheet=-1|OwnerPartId=-1|Location.X=1078|Location.Y=656|Color=8388608|FontID=1|IsHidden=T|Text=CAP_0402_0.1UF_50V|Name=Comment|ReadOnlyState=1
|RECORD=44|OwnerIndex=99
|RECORD=45|OwnerIndex=129|IndexInSheet=-1|Description=Chip Capacitor, 0402, 2-Leads, Body 1.00x0.50mm, IPC Medium Density|UseComponentLibrary=T|ModelName=CAPC1005X06N|ModelType=PCBLIB|DatafileCount=1|ModelDatafileEntity0=CAPC1005X06N|ModelDatafileKind0=PCBLib|IsCurrent=T|DatalinksLocked=T|DatabaseDatalinksLocked=T|IntegratedModel=T|DatabaseModel=T
|RECORD=46|OwnerIndex=130
|RECORD=48|OwnerIndex=130
|RECORD=1|LibReference=CAP_0402_0.1UF_50V|ComponentDescription=CAP, CER, 0.1UF, 50V, 10%, X7R, AEC-Q200, 0402|PartCount=2|DisplayModeCount=1|IndexInSheet=35|OwnerPartId=-1|Location.X=1090|Location.Y=640|Orientation=1|CurrentPartId=1|LibraryPath=*|SourceLibraryName=Capacitors.IntLib|TargetFileName=*|AreaColor=11599871|Color=128|PartIDLocked=F|DesignItemId=CAP_0402_0.1UF_50V|AllPinCount=2
|RECORD=41|OwnerIndex=133|OwnerPartId=-1|Location.X=1038|Location.Y=666|Color=8388608|FontID=7|IsHidden=T|Text=CAP, CER|Name=CATEGORY
|RECORD=41|OwnerIndex=133|IndexInSheet=1|OwnerPartId=-1|Location.X=1038|Location.Y=666|Color=8388608|FontID=7|IsHidden=T|Text=TDK|Name=MFG NAME
|RECORD=41|OwnerIndex=133|IndexInSheet=2|OwnerPartId=-1|Location.X=1038|Location.Y=666|Color=8388608|FontID=7|IsHidden=T|Text=CGA2B3X7R1H104K050BB|Name=MFG PART NUM
|RECORD=41|OwnerIndex=133|IndexInSheet=3|OwnerPartId=-1|Location.X=1038|Location.Y=666|Color=8388608|FontID=7|IsHidden=T|Text=10/23/2013|Name=MODIFY DATE
|RECORD=41|OwnerIndex=133|IndexInSheet=4|OwnerPartId=-1|Location.X=1038|Location.Y=666|Color=8388608|FontID=7|IsHidden=T|Name=Date
|RECORD=41|OwnerIndex=133|IndexInSheet=5|OwnerPartId=-1|Location.X=1038|Location.Y=666|Color=8388608|FontID=7|IsHidden=T|Text=*|Name=SHEETPART
|RECORD=41|OwnerIndex=133|IndexInSheet=6|OwnerPartId=-1|Location.X=1038|Location.Y=666|Color=8388608|FontID=7|IsHidden=T|Text=10%|Name=P1
|RECORD=41|OwnerIndex=133|IndexInSheet=7|OwnerPartId=-1|Location.X=1038|Location.Y=666|Color=8388608|FontID=7|IsHidden=T|Text=125C|Name=MAXTEMP
|RECORD=41|OwnerIndex=133|IndexInSheet=8|OwnerPartId=-1|Location.X=1038|Location.Y=666|Color=8388608|FontID=7|IsHidden=T|Text=-55C|Name=MINTEMP
|RECORD=41|OwnerIndex=133|IndexInSheet=9|OwnerPartId=-1|Location.X=1038|Location.Y=666|Color=8388608|FontID=7|IsHidden=T|Text=AEC-Q200|Name=OTHER
|RECORD=41|OwnerIndex=133|IndexInSheet=10|OwnerPartId=-1|Location.X=1038|Location.Y=666|Color=8388608|FontID=7|IsHidden=T|Text=50V|Name=P2
|RECORD=41|OwnerIndex=133|IndexInSheet=11|OwnerPartId=-1|Location.X=1038|Location.Y=666|Color=8388608|FontID=7|IsHidden=T|Text=X7R|Name=P3
|RECORD=41|OwnerIndex=133|IndexInSheet=12|OwnerPartId=-1|Location.X=1038|Location.Y=666|Color=8388608|FontID=7|IsHidden=T|Text=0402|Name=Size
|RECORD=41|OwnerIndex=133|IndexInSheet=13|OwnerPartId=-1|Location.X=1038|Location.Y=666|Color=8388608|FontID=7|IsHidden=T|Name=SUB
|RECORD=41|OwnerIndex=133|IndexInSheet=14|OwnerPartId=-1|Location.X=1038|Location.Y=666|Color=8388608|FontID=1|IsHidden=T|Text=CAP, CER, 0.1UF, 50V, 10%, X7R, AEC-Q200, 0402|Name=DESC
|RECORD=41|OwnerIndex=133|IndexInSheet=15|OwnerPartId=-1|Location.X=1038|Location.Y=666|Color=8388608|FontID=1|IsHidden=T|Text=Digi-Key|Name=Supplier 1|ReadOnlyState=3
|RECORD=41|OwnerIndex=133|IndexInSheet=16|OwnerPartId=-1|Location.X=1038|Location.Y=666|Color=8388608|FontID=1|IsHidden=T|Text=445-6899-1-ND|Name=Supplier Part Number 1|ReadOnlyState=3
|RECORD=41|OwnerIndex=133|IndexInSheet=17|OwnerPartId=-1|Location.X=1060|Location.Y=660|Color=8388608|FontID=7|Text=0.1UF|Name=VALUE
|RECORD=2|OwnerIndex=133|OwnerPartId=1|FormalType=1|Electrical=4|PinConglomerate=32|PinLength=10|Location.X=1060|Location.Y=660|Name=2|Designator=2|SwapIdPin=2|SwapIDPart=1|PinPropagationDelay=0.000000E+000
|RECORD=2|OwnerIndex=133|OwnerPartId=1|FormalType=1|Electrical=4|PinConglomerate=34|PinLength=10|Location.X=1050|Location.Y=660|Name=1|Designator=1|SwapIdPin=1|SwapIDPart=1|PinPropagationDelay=0.000000E+000
|RECORD=13|OwnerIndex=133|IsNotAccesible=T|IndexInSheet=20|OwnerPartId=1|Location.X=1057|Location.X_Frac=50000|Location.Y=660|Corner.X=1060|Corner.Y=660|LineWidth=1|Color=16711680
|RECORD=13|OwnerIndex=133|IsNotAccesible=T|IndexInSheet=21|OwnerPartId=1|Location.X=1050|Location.Y=660|Corner.X=1052|Corner.X_Frac=50000|Corner.Y=660|LineWidth=1|Color=16711680
|RECORD=13|OwnerIndex=133|IsNotAccesible=T|IndexInSheet=22|OwnerPartId=1|Location.X=1057|Location.X_Frac=50000|Location.Y=665|Corner.X=1057|Corner.X_Frac=50000|Corner.Y=655|LineWidth=1|Color=16711680
|RECORD=13|OwnerIndex=133|IsNotAccesible=T|IndexInSheet=23|OwnerPartId=1|Location.X=1052|Location.X_Frac=50000|Location.Y=665|Corner.X=1052|Corner.X_Frac=50000|Corner.Y=655|LineWidth=1|Color=16711680
|RECORD=41|OwnerIndex=133|IndexInSheet=24|OwnerPartId=-1|Location.X=1038|Location.Y=666|Color=8388608|FontID=1|IsHidden=T|Text=<VALENTIUM>|Name=VALENTIUM PART NUM
|RECORD=34|OwnerIndex=133|IndexInSheet=-1|OwnerPartId=-1|Location.X=1030|Location.Y=660|Color=8388608|FontID=1|Text=C52|Name=Designator|ReadOnlyState=1
|RECORD=41|OwnerIndex=133|IndexInSheet=-1|OwnerPartId=-1|Location.X=1038|Location.Y=666|Color=8388608|FontID=1|IsHidden=T|Text=CAP_0402_0.1UF_50V|Name=Comment|ReadOnlyState=1
|RECORD=44|OwnerIndex=133
|RECORD=45|OwnerIndex=163|IndexInSheet=-1|Description=Chip Capacitor, 0402, 2-Leads, Body 1.00x0.50mm, IPC Medium Density|UseComponentLibrary=T|ModelName=CAPC1005X06N|ModelType=PCBLIB|DatafileCount=1|ModelDatafileEntity0=CAPC1005X06N|ModelDatafileKind0=PCBLib|IsCurrent=T|DatalinksLocked=T|DatabaseDatalinksLocked=T|IntegratedModel=T|DatabaseModel=T
|RECORD=46|OwnerIndex=164
|RECORD=48|OwnerIndex=164
|RECORD=1|LibReference=RES_0402_0|ComponentDescription=RES, 0. OHM, 1%, 1/16W, TF, AEC-Q200, 0402|PartCount=2|DisplayModeCount=1|IndexInSheet=36|OwnerPartId=-1|Location.X=670|Location.Y=640|CurrentPartId=1|LibraryPath=*|SourceLibraryName=Resistors.IntLib|TargetFileName=*|AreaColor=11599871|Color=128|PartIDLocked=F|DesignItemId=RES_0402_0|AllPinCount=2
|RECORD=41|OwnerIndex=167|OwnerPartId=-1|Location.X=670|Location.Y=640|Color=8388608|FontID=7|IsHidden=T|Text=7/25/2013|Name=ModifyDate
|RECORD=41|OwnerIndex=167|IndexInSheet=1|OwnerPartId=-1|Location.X=670|Location.Y=640|Color=8388608|FontID=7|IsHidden=T|Text=ERJ-2GE0R00X|Name=MFG PART NUM
|RECORD=41|OwnerIndex=167|IndexInSheet=2|OwnerPartId=-1|Location.X=670|Location.Y=640|Color=8388608|FontID=7|IsHidden=T|Text=PANASONIC|Name=MFG NAME
|RECORD=41|OwnerIndex=167|IndexInSheet=3|OwnerPartId=-1|Location.X=670|Location.Y=640|Color=8388608|FontID=7|IsHidden=T|Text=RES|Name=CATEGORY
|RECORD=41|OwnerIndex=167|IndexInSheet=4|OwnerPartId=-1|Location.X=668|Location.Y=650|Color=8388608|FontID=7|IsHidden=T|Text=7/26/2013|Name=Date
|RECORD=41|OwnerIndex=167|IndexInSheet=5|OwnerPartId=-1|Location.X=660|Location.X_Frac=55769|Location.Y=650|Color=8388608|FontID=7|IsHidden=T|Text=1%|Name=P1
|RECORD=41|OwnerIndex=167|IndexInSheet=6|OwnerPartId=-1|Location.X=660|Location.X_Frac=55769|Location.Y=650|Color=8388608|FontID=7|IsHidden=T|Text=TF|Name=P3
|RECORD=41|OwnerIndex=167|IndexInSheet=7|OwnerPartId=-1|Location.X=660|Location.X_Frac=55769|Location.Y=650|Color=8388608|FontID=7|IsHidden=T|Text=1/16W|Name=P2
|RECORD=41|OwnerIndex=167|IndexInSheet=8|OwnerPartId=-1|Location.X=660|Location.X_Frac=55769|Location.Y=650|Color=8388608|FontID=7|IsHidden=T|Text=155C|Name=MAXTEMP
|RECORD=41|OwnerIndex=167|IndexInSheet=9|OwnerPartId=-1|Location.X=660|Location.X_Frac=55769|Location.Y=650|Color=8388608|FontID=7|IsHidden=T|Text=-55C|Name=MINTEMP
|RECORD=41|OwnerIndex=167|IndexInSheet=10|OwnerPartId=-1|Location.X=660|Location.X_Frac=55769|Location.Y=650|Color=8388608|FontID=7|IsHidden=T|Text=100PPM, AEC-Q200|Name=OTHER
|RECORD=41|OwnerIndex=167|IndexInSheet=11|OwnerPartId=-1|Location.X=660|Location.X_Frac=55769|Location.Y=650|Color=8388608|FontID=7|IsHidden=T|Text=0402|Name=SIZE
|RECORD=41|OwnerIndex=167|IndexInSheet=12|OwnerPartId=-1|Location.X=660|Location.X_Frac=55769|Location.Y=650|Color=8388608|FontID=7|IsHidden=T|Text=GENERIC|Name=SUB
|RECORD=41|OwnerIndex=167|IndexInSheet=13|OwnerPartId=-1|Location.X=655|Location.X_Frac=98077|Location.Y=626|Color=8388608|FontID=1|IsHidden=T|Text=*|Name=SHEETPART
|RECORD=41|OwnerIndex=167|IndexInSheet=14|OwnerPartId=-1|Location.X=655|Location.X_Frac=98077|Location.Y=654|Color=8388608|FontID=1|IsHidden=T|Text=RES, 0 OHM, 1%, 1/16W, TF, AEC-Q200, 0402|Name=DESC
|RECORD=41|OwnerIndex=167|IndexInSheet=15|OwnerPartId=-1|Location.X=656|Location.X_Frac=60577|Location.Y=654|Color=8388608|FontID=1|IsHidden=T|Text=Digi-Key|Name=Supplier 1|ReadOnlyState=3
|RECORD=41|OwnerIndex=167|IndexInSheet=16|OwnerPartId=-1|Location.X=656|Location.X_Frac=60577|Location.Y=654|Color=8388608|FontID=1|IsHidden=T|Text=P0.0JCT-ND|Name=Supplier Part Number 1|ReadOnlyState=3
|RECORD=41|OwnerIndex=167|IndexInSheet=17|OwnerPartId=-1|Location.X=656|Location.X_Frac=61102|Location.Y=654|Color=8388608|FontID=1|IsHidden=T|Text=<VELENTIUM>|Name=VELENTIUM PART NUM
|RECORD=41|OwnerIndex=167|IndexInSheet=18|OwnerPartId=-1|Location.X=679|Location.Y=624|Color=8388608|FontID=7|Text=0 OHM|Name=VALUE
|RECORD=2|OwnerIndex=167|OwnerPartId=1|FormalType=1|Electrical=4|PinConglomerate=34|PinLength=10|Location.X=680|Location.Y=640|Name=1|Designator=1|PinPropagationDelay=0.000000E+000
|RECORD=2|OwnerIndex=167|OwnerPartId=1|FormalType=1|Electrical=4|PinConglomerate=32|PinLength=10|Location.X=710|Location.Y=640|Name=2|Designator=2|PinPropagationDelay=0.000000E+000
|RECORD=6|OwnerIndex=167|IsNotAccesible=T|IndexInSheet=21|OwnerPartId=1|LineWidth=1|Color=16711680|LocationCount=7|X1=710|Y1=640|X2=707|Y2=643|X3=701|Y3=637|X4=695|Y4=643|X5=689|Y5=637|X6=683|Y6=643|X7=680|Y7=640
|RECORD=34|OwnerIndex=167|IndexInSheet=-1|OwnerPartId=-1|Location.X=679|Location.Y=644|Color=8388608|FontID=1|Text=R24|Name=Designator|ReadOnlyState=1
|RECORD=41|OwnerIndex=167|IndexInSheet=-1|OwnerPartId=-1|Location.X=690|Location.Y=630|Color=8388608|FontID=1|IsHidden=T|Text=="MFG PART NUM"|Name=Comment
|RECORD=44|OwnerIndex=167
|RECORD=45|OwnerIndex=194|IndexInSheet=-1|Description=Chip Resistor, 0402, 2-Leads, Body 1.00x0.50mm, IPC Medium Density|UseComponentLibrary=T|ModelName=RESC1005X04N|ModelType=PCBLIB|DatafileCount=1|ModelDatafileEntity0=RESC1005X04N|ModelDatafileKind0=PCBLib|IsCurrent=T|DatalinksLocked=T|DatabaseDatalinksLocked=T|IntegratedModel=T|DatabaseModel=T
|RECORD=46|OwnerIndex=195
|RECORD=48|OwnerIndex=195
|RECORD=1|LibReference=RES_0402_0|ComponentDescription=RES, 0. OHM, 1%, 1/16W, TF, AEC-Q200, 0402|PartCount=2|DisplayModeCount=1|IndexInSheet=37|OwnerPartId=-1|Location.X=670|Location.Y=780|CurrentPartId=1|LibraryPath=*|SourceLibraryName=Resistors.IntLib|TargetFileName=*|AreaColor=11599871|Color=128|PartIDLocked=F|DesignItemId=RES_0402_0|AllPinCount=2
|RECORD=41|OwnerIndex=198|OwnerPartId=-1|Location.X=670|Location.Y=780|Color=8388608|FontID=7|IsHidden=T|Text=7/25/2013|Name=ModifyDate
|RECORD=41|OwnerIndex=198|IndexInSheet=1|OwnerPartId=-1|Location.X=670|Location.Y=780|Color=8388608|FontID=7|IsHidden=T|Text=ERJ-2GE0R00X|Name=MFG PART NUM
|RECORD=41|OwnerIndex=198|IndexInSheet=2|OwnerPartId=-1|Location.X=670|Location.Y=780|Color=8388608|FontID=7|IsHidden=T|Text=PANASONIC|Name=MFG NAME
|RECORD=41|OwnerIndex=198|IndexInSheet=3|OwnerPartId=-1|Location.X=670|Location.Y=780|Color=8388608|FontID=7|IsHidden=T|Text=RES|Name=CATEGORY
|RECORD=41|OwnerIndex=198|IndexInSheet=4|OwnerPartId=-1|Location.X=668|Location.Y=790|Color=8388608|FontID=7|IsHidden=T|Text=7/26/2013|Name=Date
|RECORD=41|OwnerIndex=198|IndexInSheet=5|OwnerPartId=-1|Location.X=660|Location.X_Frac=55769|Location.Y=790|Color=8388608|FontID=7|IsHidden=T|Text=1%|Name=P1
|RECORD=41|OwnerIndex=198|IndexInSheet=6|OwnerPartId=-1|Location.X=660|Location.X_Frac=55769|Location.Y=790|Color=8388608|FontID=7|IsHidden=T|Text=TF|Name=P3
|RECORD=41|OwnerIndex=198|IndexInSheet=7|OwnerPartId=-1|Location.X=660|Location.X_Frac=55769|Location.Y=790|Color=8388608|FontID=7|IsHidden=T|Text=1/16W|Name=P2
|RECORD=41|OwnerIndex=198|IndexInSheet=8|OwnerPartId=-1|Location.X=660|Location.X_Frac=55769|Location.Y=790|Color=8388608|FontID=7|IsHidden=T|Text=155C|Name=MAXTEMP
|RECORD=41|OwnerIndex=198|IndexInSheet=9|OwnerPartId=-1|Location.X=660|Location.X_Frac=55769|Location.Y=790|Color=8388608|FontID=7|IsHidden=T|Text=-55C|Name=MINTEMP
|RECORD=41|OwnerIndex=198|IndexInSheet=10|OwnerPartId=-1|Location.X=660|Location.X_Frac=55769|Location.Y=790|Color=8388608|FontID=7|IsHidden=T|Text=100PPM, AEC-Q200|Name=OTHER
|RECORD=41|OwnerIndex=198|IndexInSheet=11|OwnerPartId=-1|Location.X=660|Location.X_Frac=55769|Location.Y=790|Color=8388608|FontID=7|IsHidden=T|Text=0402|Name=SIZE
|RECORD=41|OwnerIndex=198|IndexInSheet=12|OwnerPartId=-1|Location.X=660|Location.X_Frac=55769|Location.Y=790|Color=8388608|FontID=7|IsHidden=T|Text=GENERIC|Name=SUB
|RECORD=41|OwnerIndex=198|IndexInSheet=13|OwnerPartId=-1|Location.X=655|Location.X_Frac=98077|Location.Y=766|Color=8388608|FontID=1|IsHidden=T|Text=*|Name=SHEETPART
|RECORD=41|OwnerIndex=198|IndexInSheet=14|OwnerPartId=-1|Location.X=655|Location.X_Frac=98077|Location.Y=794|Color=8388608|FontID=1|IsHidden=T|Text=RES, 0 OHM, 1%, 1/16W, TF, AEC-Q200, 0402|Name=DESC
|RECORD=41|OwnerIndex=198|IndexInSheet=15|OwnerPartId=-1|Location.X=656|Location.X_Frac=60577|Location.Y=794|Color=8388608|FontID=1|IsHidden=T|Text=Digi-Key|Name=Supplier 1|ReadOnlyState=3
|RECORD=41|OwnerIndex=198|IndexInSheet=16|OwnerPartId=-1|Location.X=656|Location.X_Frac=60577|Location.Y=794|Color=8388608|FontID=1|IsHidden=T|Text=P0.0JCT-ND|Name=Supplier Part Number 1|ReadOnlyState=3
|RECORD=41|OwnerIndex=198|IndexInSheet=17|OwnerPartId=-1|Location.X=656|Location.X_Frac=61102|Location.Y=794|Color=8388608|FontID=1|IsHidden=T|Text=<VELENTIUM>|Name=VELENTIUM PART NUM
|RECORD=41|OwnerIndex=198|IndexInSheet=18|OwnerPartId=-1|Location.X=679|Location.Y=764|Color=8388608|FontID=7|Text=0 OHM|Name=VALUE
|RECORD=2|OwnerIndex=198|OwnerPartId=1|FormalType=1|Electrical=4|PinConglomerate=34|PinLength=10|Location.X=680|Location.Y=780|Name=1|Designator=1|PinPropagationDelay=0.000000E+000
|RECORD=2|OwnerIndex=198|OwnerPartId=1|FormalType=1|Electrical=4|PinConglomerate=32|PinLength=10|Location.X=710|Location.Y=780|Name=2|Designator=2|PinPropagationDelay=0.000000E+000
|RECORD=6|OwnerIndex=198|IsNotAccesible=T|IndexInSheet=21|OwnerPartId=1|LineWidth=1|Color=16711680|LocationCount=7|X1=710|Y1=780|X2=707|Y2=783|X3=701|Y3=777|X4=695|Y4=783|X5=689|Y5=777|X6=683|Y6=783|X7=680|Y7=780
|RECORD=34|OwnerIndex=198|IndexInSheet=-1|OwnerPartId=-1|Location.X=679|Location.Y=784|Color=8388608|FontID=1|Text=R23|Name=Designator|ReadOnlyState=1
|RECORD=41|OwnerIndex=198|IndexInSheet=-1|OwnerPartId=-1|Location.X=690|Location.Y=770|Color=8388608|FontID=1|IsHidden=T|Text=="MFG PART NUM"|Name=Comment
|RECORD=44|OwnerIndex=198
|RECORD=45|OwnerIndex=225|IndexInSheet=-1|Description=Chip Resistor, 0402, 2-Leads, Body 1.00x0.50mm, IPC Medium Density|UseComponentLibrary=T|ModelName=RESC1005X04N|ModelType=PCBLIB|DatafileCount=1|ModelDatafileEntity0=RESC1005X04N|ModelDatafileKind0=PCBLib|IsCurrent=T|DatalinksLocked=T|DatabaseDatalinksLocked=T|IntegratedModel=T|DatabaseModel=T
|RECORD=46|OwnerIndex=226
|RECORD=48|OwnerIndex=226
|RECORD=1|LibReference=CAP_0402_0.1UF_50V|ComponentDescription=CAP, CER, 0.1UF, 50V, 10%, X7R, AEC-Q200, 0402|PartCount=2|DisplayModeCount=1|IndexInSheet=38|OwnerPartId=-1|Location.X=1130|Location.Y=670|Orientation=1|CurrentPartId=1|LibraryPath=*|SourceLibraryName=Capacitors.IntLib|TargetFileName=*|AreaColor=11599871|Color=128|PartIDLocked=F|DesignItemId=CAP_0402_0.1UF_50V|AllPinCount=2
|RECORD=41|OwnerIndex=229|OwnerPartId=-1|Location.X=1078|Location.Y=696|Color=8388608|FontID=7|IsHidden=T|Text=CAP, CER|Name=CATEGORY
|RECORD=41|OwnerIndex=229|IndexInSheet=1|OwnerPartId=-1|Location.X=1078|Location.Y=696|Color=8388608|FontID=7|IsHidden=T|Text=TDK|Name=MFG NAME
|RECORD=41|OwnerIndex=229|IndexInSheet=2|OwnerPartId=-1|Location.X=1078|Location.Y=696|Color=8388608|FontID=7|IsHidden=T|Text=CGA2B3X7R1H104K050BB|Name=MFG PART NUM
|RECORD=41|OwnerIndex=229|IndexInSheet=3|OwnerPartId=-1|Location.X=1078|Location.Y=696|Color=8388608|FontID=7|IsHidden=T|Text=10/23/2013|Name=MODIFY DATE
|RECORD=41|OwnerIndex=229|IndexInSheet=4|OwnerPartId=-1|Location.X=1078|Location.Y=696|Color=8388608|FontID=7|IsHidden=T|Name=Date
|RECORD=41|OwnerIndex=229|IndexInSheet=5|OwnerPartId=-1|Location.X=1078|Location.Y=696|Color=8388608|FontID=7|IsHidden=T|Text=*|Name=SHEETPART
|RECORD=41|OwnerIndex=229|IndexInSheet=6|OwnerPartId=-1|Location.X=1078|Location.Y=696|Color=8388608|FontID=7|IsHidden=T|Text=10%|Name=P1
|RECORD=41|OwnerIndex=229|IndexInSheet=7|OwnerPartId=-1|Location.X=1078|Location.Y=696|Color=8388608|FontID=7|IsHidden=T|Text=125C|Name=MAXTEMP
|RECORD=41|OwnerIndex=229|IndexInSheet=8|OwnerPartId=-1|Location.X=1078|Location.Y=696|Color=8388608|FontID=7|IsHidden=T|Text=-55C|Name=MINTEMP
|RECORD=41|OwnerIndex=229|IndexInSheet=9|OwnerPartId=-1|Location.X=1078|Location.Y=696|Color=8388608|FontID=7|IsHidden=T|Text=AEC-Q200|Name=OTHER
|RECORD=41|OwnerIndex=229|IndexInSheet=10|OwnerPartId=-1|Location.X=1078|Location.Y=696|Color=8388608|FontID=7|IsHidden=T|Text=50V|Name=P2
|RECORD=41|OwnerIndex=229|IndexInSheet=11|OwnerPartId=-1|Location.X=1078|Location.Y=696|Color=8388608|FontID=7|IsHidden=T|Text=X7R|Name=P3
|RECORD=41|OwnerIndex=229|IndexInSheet=12|OwnerPartId=-1|Location.X=1078|Location.Y=696|Color=8388608|FontID=7|IsHidden=T|Text=0402|Name=Size
|RECORD=41|OwnerIndex=229|IndexInSheet=13|OwnerPartId=-1|Location.X=1078|Location.Y=696|Color=8388608|FontID=7|IsHidden=T|Name=SUB
|RECORD=41|OwnerIndex=229|IndexInSheet=14|OwnerPartId=-1|Location.X=1078|Location.Y=696|Color=8388608|FontID=1|IsHidden=T|Text=CAP, CER, 0.1UF, 50V, 10%, X7R, AEC-Q200, 0402|Name=DESC
|RECORD=41|OwnerIndex=229|IndexInSheet=15|OwnerPartId=-1|Location.X=1078|Location.Y=696|Color=8388608|FontID=1|IsHidden=T|Text=Digi-Key|Name=Supplier 1|ReadOnlyState=3
|RECORD=41|OwnerIndex=229|IndexInSheet=16|OwnerPartId=-1|Location.X=1078|Location.Y=696|Color=8388608|FontID=1|IsHidden=T|Text=445-6899-1-ND|Name=Supplier Part Number 1|ReadOnlyState=3
|RECORD=41|OwnerIndex=229|IndexInSheet=17|OwnerPartId=-1|Location.X=1101|Location.Y=678|Color=8388608|FontID=7|Text=0.1UF|Name=VALUE
|RECORD=2|OwnerIndex=229|OwnerPartId=1|FormalType=1|Electrical=4|PinConglomerate=32|PinLength=10|Location.X=1100|Location.Y=690|Name=2|Designator=2|SwapIdPin=2|SwapIDPart=1|PinPropagationDelay=0.000000E+000
|RECORD=2|OwnerIndex=229|OwnerPartId=1|FormalType=1|Electrical=4|PinConglomerate=34|PinLength=10|Location.X=1090|Location.Y=690|Name=1|Designator=1|SwapIdPin=1|SwapIDPart=1|PinPropagationDelay=0.000000E+000
|RECORD=13|OwnerIndex=229|IsNotAccesible=T|IndexInSheet=20|OwnerPartId=1|Location.X=1097|Location.X_Frac=50000|Location.Y=690|Corner.X=1100|Corner.Y=690|LineWidth=1|Color=16711680
|RECORD=13|OwnerIndex=229|IsNotAccesible=T|IndexInSheet=21|OwnerPartId=1|Location.X=1090|Location.Y=690|Corner.X=1092|Corner.X_Frac=50000|Corner.Y=690|LineWidth=1|Color=16711680
|RECORD=13|OwnerIndex=229|IsNotAccesible=T|IndexInSheet=22|OwnerPartId=1|Location.X=1097|Location.X_Frac=50000|Location.Y=695|Corner.X=1097|Corner.X_Frac=50000|Corner.Y=685|LineWidth=1|Color=16711680
|RECORD=13|OwnerIndex=229|IsNotAccesible=T|IndexInSheet=23|OwnerPartId=1|Location.X=1092|Location.X_Frac=50000|Location.Y=695|Corner.X=1092|Corner.X_Frac=50000|Corner.Y=685|LineWidth=1|Color=16711680
|RECORD=41|OwnerIndex=229|IndexInSheet=24|OwnerPartId=-1|Location.X=1078|Location.Y=696|Color=8388608|FontID=1|IsHidden=T|Text=<VALENTIUM>|Name=VALENTIUM PART NUM
|RECORD=34|OwnerIndex=229|IndexInSheet=-1|OwnerPartId=-1|Location.X=1070|Location.Y=676|Color=8388608|FontID=1|Text=C51|Name=Designator|ReadOnlyState=1
|RECORD=41|OwnerIndex=229|IndexInSheet=-1|OwnerPartId=-1|Location.X=1078|Location.Y=696|Color=8388608|FontID=1|IsHidden=T|Text=CAP_0402_0.1UF_50V|Name=Comment|ReadOnlyState=1
|RECORD=44|OwnerIndex=229
|RECORD=45|OwnerIndex=259|IndexInSheet=-1|Description=Chip Capacitor, 0402, 2-Leads, Body 1.00x0.50mm, IPC Medium Density|UseComponentLibrary=T|ModelName=CAPC1005X06N|ModelType=PCBLIB|DatafileCount=1|ModelDatafileEntity0=CAPC1005X06N|ModelDatafileKind0=PCBLib|IsCurrent=T|DatalinksLocked=T|DatabaseDatalinksLocked=T|IntegratedModel=T|DatabaseModel=T
|RECORD=46|OwnerIndex=260
|RECORD=48|OwnerIndex=260
|RECORD=1|LibReference=CAP_0402_0.1UF_50V|ComponentDescription=CAP, CER, 0.1UF, 50V, 10%, X7R, AEC-Q200, 0402|PartCount=2|DisplayModeCount=1|IndexInSheet=39|OwnerPartId=-1|Location.X=1130|Location.Y=710|Orientation=1|CurrentPartId=1|LibraryPath=*|SourceLibraryName=Capacitors.IntLib|TargetFileName=*|AreaColor=11599871|Color=128|PartIDLocked=F|DesignItemId=CAP_0402_0.1UF_50V|AllPinCount=2
|RECORD=41|OwnerIndex=263|OwnerPartId=-1|Location.X=1078|Location.Y=736|Color=8388608|FontID=7|IsHidden=T|Text=CAP, CER|Name=CATEGORY
|RECORD=41|OwnerIndex=263|IndexInSheet=1|OwnerPartId=-1|Location.X=1078|Location.Y=736|Color=8388608|FontID=7|IsHidden=T|Text=TDK|Name=MFG NAME
|RECORD=41|OwnerIndex=263|IndexInSheet=2|OwnerPartId=-1|Location.X=1078|Location.Y=736|Color=8388608|FontID=7|IsHidden=T|Text=CGA2B3X7R1H104K050BB|Name=MFG PART NUM
|RECORD=41|OwnerIndex=263|IndexInSheet=3|OwnerPartId=-1|Location.X=1078|Location.Y=736|Color=8388608|FontID=7|IsHidden=T|Text=10/23/2013|Name=MODIFY DATE
|RECORD=41|OwnerIndex=263|IndexInSheet=4|OwnerPartId=-1|Location.X=1078|Location.Y=736|Color=8388608|FontID=7|IsHidden=T|Name=Date
|RECORD=41|OwnerIndex=263|IndexInSheet=5|OwnerPartId=-1|Location.X=1078|Location.Y=736|Color=8388608|FontID=7|IsHidden=T|Text=*|Name=SHEETPART
|RECORD=41|OwnerIndex=263|IndexInSheet=6|OwnerPartId=-1|Location.X=1078|Location.Y=736|Color=8388608|FontID=7|IsHidden=T|Text=10%|Name=P1
|RECORD=41|OwnerIndex=263|IndexInSheet=7|OwnerPartId=-1|Location.X=1078|Location.Y=736|Color=8388608|FontID=7|IsHidden=T|Text=125C|Name=MAXTEMP
|RECORD=41|OwnerIndex=263|IndexInSheet=8|OwnerPartId=-1|Location.X=1078|Location.Y=736|Color=8388608|FontID=7|IsHidden=T|Text=-55C|Name=MINTEMP
|RECORD=41|OwnerIndex=263|IndexInSheet=9|OwnerPartId=-1|Location.X=1078|Location.Y=736|Color=8388608|FontID=7|IsHidden=T|Text=AEC-Q200|Name=OTHER
|RECORD=41|OwnerIndex=263|IndexInSheet=10|OwnerPartId=-1|Location.X=1078|Location.Y=736|Color=8388608|FontID=7|IsHidden=T|Text=50V|Name=P2
|RECORD=41|OwnerIndex=263|IndexInSheet=11|OwnerPartId=-1|Location.X=1078|Location.Y=736|Color=8388608|FontID=7|IsHidden=T|Text=X7R|Name=P3
|RECORD=41|OwnerIndex=263|IndexInSheet=12|OwnerPartId=-1|Location.X=1078|Location.Y=736|Color=8388608|FontID=7|IsHidden=T|Text=0402|Name=Size
|RECORD=41|OwnerIndex=263|IndexInSheet=13|OwnerPartId=-1|Location.X=1078|Location.Y=736|Color=8388608|FontID=7|IsHidden=T|Name=SUB
|RECORD=41|OwnerIndex=263|IndexInSheet=14|OwnerPartId=-1|Location.X=1078|Location.Y=736|Color=8388608|FontID=1|IsHidden=T|Text=CAP, CER, 0.1UF, 50V, 10%, X7R, AEC-Q200, 0402|Name=DESC
|RECORD=41|OwnerIndex=263|IndexInSheet=15|OwnerPartId=-1|Location.X=1078|Location.Y=736|Color=8388608|FontID=1|IsHidden=T|Text=Digi-Key|Name=Supplier 1|ReadOnlyState=3
|RECORD=41|OwnerIndex=263|IndexInSheet=16|OwnerPartId=-1|Location.X=1078|Location.Y=736|Color=8388608|FontID=1|IsHidden=T|Text=445-6899-1-ND|Name=Supplier Part Number 1|ReadOnlyState=3
|RECORD=41|OwnerIndex=263|IndexInSheet=17|OwnerPartId=-1|Location.X=1101|Location.Y=718|Color=8388608|FontID=7|Text=0.1UF|Name=VALUE
|RECORD=2|OwnerIndex=263|OwnerPartId=1|FormalType=1|Electrical=4|PinConglomerate=32|PinLength=10|Location.X=1100|Location.Y=730|Name=2|Designator=2|SwapIdPin=2|SwapIDPart=1|PinPropagationDelay=0.000000E+000
|RECORD=2|OwnerIndex=263|OwnerPartId=1|FormalType=1|Electrical=4|PinConglomerate=34|PinLength=10|Location.X=1090|Location.Y=730|Name=1|Designator=1|SwapIdPin=1|SwapIDPart=1|PinPropagationDelay=0.000000E+000
|RECORD=13|OwnerIndex=263|IsNotAccesible=T|IndexInSheet=20|OwnerPartId=1|Location.X=1097|Location.X_Frac=50000|Location.Y=730|Corner.X=1100|Corner.Y=730|LineWidth=1|Color=16711680
|RECORD=13|OwnerIndex=263|IsNotAccesible=T|IndexInSheet=21|OwnerPartId=1|Location.X=1090|Location.Y=730|Corner.X=1092|Corner.X_Frac=50000|Corner.Y=730|LineWidth=1|Color=16711680
|RECORD=13|OwnerIndex=263|IsNotAccesible=T|IndexInSheet=22|OwnerPartId=1|Location.X=1097|Location.X_Frac=50000|Location.Y=735|Corner.X=1097|Corner.X_Frac=50000|Corner.Y=725|LineWidth=1|Color=16711680
|RECORD=13|OwnerIndex=263|IsNotAccesible=T|IndexInSheet=23|OwnerPartId=1|Location.X=1092|Location.X_Frac=50000|Location.Y=735|Corner.X=1092|Corner.X_Frac=50000|Corner.Y=725|LineWidth=1|Color=16711680
|RECORD=41|OwnerIndex=263|IndexInSheet=24|OwnerPartId=-1|Location.X=1078|Location.Y=736|Color=8388608|FontID=1|IsHidden=T|Text=<VALENTIUM>|Name=VALENTIUM PART NUM
|RECORD=34|OwnerIndex=263|IndexInSheet=-1|OwnerPartId=-1|Location.X=1070|Location.Y=716|Color=8388608|FontID=1|Text=C49|Name=Designator|ReadOnlyState=1
|RECORD=41|OwnerIndex=263|IndexInSheet=-1|OwnerPartId=-1|Location.X=1078|Location.Y=736|Color=8388608|FontID=1|IsHidden=T|Text=CAP_0402_0.1UF_50V|Name=Comment|ReadOnlyState=1
|RECORD=44|OwnerIndex=263
|RECORD=45|OwnerIndex=293|IndexInSheet=-1|Description=Chip Capacitor, 0402, 2-Leads, Body 1.00x0.50mm, IPC Medium Density|UseComponentLibrary=T|ModelName=CAPC1005X06N|ModelType=PCBLIB|DatafileCount=1|ModelDatafileEntity0=CAPC1005X06N|ModelDatafileKind0=PCBLib|IsCurrent=T|DatalinksLocked=T|DatabaseDatalinksLocked=T|IntegratedModel=T|DatabaseModel=T
|RECORD=46|OwnerIndex=294
|RECORD=48|OwnerIndex=294
|RECORD=1|LibReference=CAP_0402_0.1UF_50V|ComponentDescription=CAP, CER, 0.1UF, 50V, 10%, X7R, AEC-Q200, 0402|PartCount=2|DisplayModeCount=1|IndexInSheet=40|OwnerPartId=-1|Location.X=1130|Location.Y=760|Orientation=1|CurrentPartId=1|LibraryPath=*|SourceLibraryName=Capacitors.IntLib|TargetFileName=*|AreaColor=11599871|Color=128|PartIDLocked=F|DesignItemId=CAP_0402_0.1UF_50V|AllPinCount=2
|RECORD=41|OwnerIndex=297|OwnerPartId=-1|Location.X=1078|Location.Y=786|Color=8388608|FontID=7|IsHidden=T|Text=CAP, CER|Name=CATEGORY
|RECORD=41|OwnerIndex=297|IndexInSheet=1|OwnerPartId=-1|Location.X=1078|Location.Y=786|Color=8388608|FontID=7|IsHidden=T|Text=TDK|Name=MFG NAME
|RECORD=41|OwnerIndex=297|IndexInSheet=2|OwnerPartId=-1|Location.X=1078|Location.Y=786|Color=8388608|FontID=7|IsHidden=T|Text=CGA2B3X7R1H104K050BB|Name=MFG PART NUM
|RECORD=41|OwnerIndex=297|IndexInSheet=3|OwnerPartId=-1|Location.X=1078|Location.Y=786|Color=8388608|FontID=7|IsHidden=T|Text=10/23/2013|Name=MODIFY DATE
|RECORD=41|OwnerIndex=297|IndexInSheet=4|OwnerPartId=-1|Location.X=1078|Location.Y=786|Color=8388608|FontID=7|IsHidden=T|Name=Date
|RECORD=41|OwnerIndex=297|IndexInSheet=5|OwnerPartId=-1|Location.X=1078|Location.Y=786|Color=8388608|FontID=7|IsHidden=T|Text=*|Name=SHEETPART
|RECORD=41|OwnerIndex=297|IndexInSheet=6|OwnerPartId=-1|Location.X=1078|Location.Y=786|Color=8388608|FontID=7|IsHidden=T|Text=10%|Name=P1
|RECORD=41|OwnerIndex=297|IndexInSheet=7|OwnerPartId=-1|Location.X=1078|Location.Y=786|Color=8388608|FontID=7|IsHidden=T|Text=125C|Name=MAXTEMP
|RECORD=41|OwnerIndex=297|IndexInSheet=8|OwnerPartId=-1|Location.X=1078|Location.Y=786|Color=8388608|FontID=7|IsHidden=T|Text=-55C|Name=MINTEMP
|RECORD=41|OwnerIndex=297|IndexInSheet=9|OwnerPartId=-1|Location.X=1078|Location.Y=786|Color=8388608|FontID=7|IsHidden=T|Text=AEC-Q200|Name=OTHER
|RECORD=41|OwnerIndex=297|IndexInSheet=10|OwnerPartId=-1|Location.X=1078|Location.Y=786|Color=8388608|FontID=7|IsHidden=T|Text=50V|Name=P2
|RECORD=41|OwnerIndex=297|IndexInSheet=11|OwnerPartId=-1|Location.X=1078|Location.Y=786|Color=8388608|FontID=7|IsHidden=T|Text=X7R|Name=P3
|RECORD=41|OwnerIndex=297|IndexInSheet=12|OwnerPartId=-1|Location.X=1078|Location.Y=786|Color=8388608|FontID=7|IsHidden=T|Text=0402|Name=Size
|RECORD=41|OwnerIndex=297|IndexInSheet=13|OwnerPartId=-1|Location.X=1078|Location.Y=786|Color=8388608|FontID=7|IsHidden=T|Name=SUB
|RECORD=41|OwnerIndex=297|IndexInSheet=14|OwnerPartId=-1|Location.X=1078|Location.Y=786|Color=8388608|FontID=1|IsHidden=T|Text=CAP, CER, 0.1UF, 50V, 10%, X7R, AEC-Q200, 0402|Name=DESC
|RECORD=41|OwnerIndex=297|IndexInSheet=15|OwnerPartId=-1|Location.X=1078|Location.Y=786|Color=8388608|FontID=1|IsHidden=T|Text=Digi-Key|Name=Supplier 1|ReadOnlyState=3
|RECORD=41|OwnerIndex=297|IndexInSheet=16|OwnerPartId=-1|Location.X=1078|Location.Y=786|Color=8388608|FontID=1|IsHidden=T|Text=445-6899-1-ND|Name=Supplier Part Number 1|ReadOnlyState=3
|RECORD=41|OwnerIndex=297|IndexInSheet=17|OwnerPartId=-1|Location.X=1101|Location.Y=768|Color=8388608|FontID=7|Text=0.1UF|Name=VALUE
|RECORD=2|OwnerIndex=297|OwnerPartId=1|FormalType=1|Electrical=4|PinConglomerate=32|PinLength=10|Location.X=1100|Location.Y=780|Name=2|Designator=2|SwapIdPin=2|SwapIDPart=1|PinPropagationDelay=0.000000E+000
|RECORD=2|OwnerIndex=297|OwnerPartId=1|FormalType=1|Electrical=4|PinConglomerate=34|PinLength=10|Location.X=1090|Location.Y=780|Name=1|Designator=1|SwapIdPin=1|SwapIDPart=1|PinPropagationDelay=0.000000E+000
|RECORD=13|OwnerIndex=297|IsNotAccesible=T|IndexInSheet=20|OwnerPartId=1|Location.X=1097|Location.X_Frac=50000|Location.Y=780|Corner.X=1100|Corner.Y=780|LineWidth=1|Color=16711680
|RECORD=13|OwnerIndex=297|IsNotAccesible=T|IndexInSheet=21|OwnerPartId=1|Location.X=1090|Location.Y=780|Corner.X=1092|Corner.X_Frac=50000|Corner.Y=780|LineWidth=1|Color=16711680
|RECORD=13|OwnerIndex=297|IsNotAccesible=T|IndexInSheet=22|OwnerPartId=1|Location.X=1097|Location.X_Frac=50000|Location.Y=785|Corner.X=1097|Corner.X_Frac=50000|Corner.Y=775|LineWidth=1|Color=16711680
|RECORD=13|OwnerIndex=297|IsNotAccesible=T|IndexInSheet=23|OwnerPartId=1|Location.X=1092|Location.X_Frac=50000|Location.Y=785|Corner.X=1092|Corner.X_Frac=50000|Corner.Y=775|LineWidth=1|Color=16711680
|RECORD=41|OwnerIndex=297|IndexInSheet=24|OwnerPartId=-1|Location.X=1078|Location.Y=786|Color=8388608|FontID=1|IsHidden=T|Text=<VALENTIUM>|Name=VALENTIUM PART NUM
|RECORD=34|OwnerIndex=297|IndexInSheet=-1|OwnerPartId=-1|Location.X=1070|Location.Y=766|Color=8388608|FontID=1|Text=C47|Name=Designator|ReadOnlyState=1
|RECORD=41|OwnerIndex=297|IndexInSheet=-1|OwnerPartId=-1|Location.X=1078|Location.Y=786|Color=8388608|FontID=1|IsHidden=T|Text=CAP_0402_0.1UF_50V|Name=Comment|ReadOnlyState=1
|RECORD=44|OwnerIndex=297
|RECORD=45|OwnerIndex=327|IndexInSheet=-1|Description=Chip Capacitor, 0402, 2-Leads, Body 1.00x0.50mm, IPC Medium Density|UseComponentLibrary=T|ModelName=CAPC1005X06N|ModelType=PCBLIB|DatafileCount=1|ModelDatafileEntity0=CAPC1005X06N|ModelDatafileKind0=PCBLib|IsCurrent=T|DatalinksLocked=T|DatabaseDatalinksLocked=T|IntegratedModel=T|DatabaseModel=T
|RECORD=46|OwnerIndex=328
|RECORD=48|OwnerIndex=328
|RECORD=1|LibReference=CAP_0402_0.1UF_50V|ComponentDescription=CAP, CER, 0.1UF, 50V, 10%, X7R, AEC-Q200, 0402|PartCount=2|DisplayModeCount=1|IndexInSheet=41|OwnerPartId=-1|Location.X=1130|Location.Y=790|Orientation=1|CurrentPartId=1|LibraryPath=*|SourceLibraryName=Capacitors.IntLib|TargetFileName=*|AreaColor=11599871|Color=128|PartIDLocked=F|DesignItemId=CAP_0402_0.1UF_50V|AllPinCount=2
|RECORD=41|OwnerIndex=331|OwnerPartId=-1|Location.X=1078|Location.Y=816|Color=8388608|FontID=7|IsHidden=T|Text=CAP, CER|Name=CATEGORY
|RECORD=41|OwnerIndex=331|IndexInSheet=1|OwnerPartId=-1|Location.X=1078|Location.Y=816|Color=8388608|FontID=7|IsHidden=T|Text=TDK|Name=MFG NAME
|RECORD=41|OwnerIndex=331|IndexInSheet=2|OwnerPartId=-1|Location.X=1078|Location.Y=816|Color=8388608|FontID=7|IsHidden=T|Text=CGA2B3X7R1H104K050BB|Name=MFG PART NUM
|RECORD=41|OwnerIndex=331|IndexInSheet=3|OwnerPartId=-1|Location.X=1078|Location.Y=816|Color=8388608|FontID=7|IsHidden=T|Text=10/23/2013|Name=MODIFY DATE
|RECORD=41|OwnerIndex=331|IndexInSheet=4|OwnerPartId=-1|Location.X=1078|Location.Y=816|Color=8388608|FontID=7|IsHidden=T|Name=Date
|RECORD=41|OwnerIndex=331|IndexInSheet=5|OwnerPartId=-1|Location.X=1078|Location.Y=816|Color=8388608|FontID=7|IsHidden=T|Text=*|Name=SHEETPART
|RECORD=41|OwnerIndex=331|IndexInSheet=6|OwnerPartId=-1|Location.X=1078|Location.Y=816|Color=8388608|FontID=7|IsHidden=T|Text=10%|Name=P1
|RECORD=41|OwnerIndex=331|IndexInSheet=7|OwnerPartId=-1|Location.X=1078|Location.Y=816|Color=8388608|FontID=7|IsHidden=T|Text=125C|Name=MAXTEMP
|RECORD=41|OwnerIndex=331|IndexInSheet=8|OwnerPartId=-1|Location.X=1078|Location.Y=816|Color=8388608|FontID=7|IsHidden=T|Text=-55C|Name=MINTEMP
|RECORD=41|OwnerIndex=331|IndexInSheet=9|OwnerPartId=-1|Location.X=1078|Location.Y=816|Color=8388608|FontID=7|IsHidden=T|Text=AEC-Q200|Name=OTHER
|RECORD=41|OwnerIndex=331|IndexInSheet=10|OwnerPartId=-1|Location.X=1078|Location.Y=816|Color=8388608|FontID=7|IsHidden=T|Text=50V|Name=P2
|RECORD=41|OwnerIndex=331|IndexInSheet=11|OwnerPartId=-1|Location.X=1078|Location.Y=816|Color=8388608|FontID=7|IsHidden=T|Text=X7R|Name=P3
|RECORD=41|OwnerIndex=331|IndexInSheet=12|OwnerPartId=-1|Location.X=1078|Location.Y=816|Color=8388608|FontID=7|IsHidden=T|Text=0402|Name=Size
|RECORD=41|OwnerIndex=331|IndexInSheet=13|OwnerPartId=-1|Location.X=1078|Location.Y=816|Color=8388608|FontID=7|IsHidden=T|Name=SUB
|RECORD=41|OwnerIndex=331|IndexInSheet=14|OwnerPartId=-1|Location.X=1078|Location.Y=816|Color=8388608|FontID=1|IsHidden=T|Text=CAP, CER, 0.1UF, 50V, 10%, X7R, AEC-Q200, 0402|Name=DESC
|RECORD=41|OwnerIndex=331|IndexInSheet=15|OwnerPartId=-1|Location.X=1078|Location.Y=816|Color=8388608|FontID=1|IsHidden=T|Text=Digi-Key|Name=Supplier 1|ReadOnlyState=3
|RECORD=41|OwnerIndex=331|IndexInSheet=16|OwnerPartId=-1|Location.X=1078|Location.Y=816|Color=8388608|FontID=1|IsHidden=T|Text=445-6899-1-ND|Name=Supplier Part Number 1|ReadOnlyState=3
|RECORD=41|OwnerIndex=331|IndexInSheet=17|OwnerPartId=-1|Location.X=1101|Location.Y=798|Color=8388608|FontID=7|Text=0.1UF|Name=VALUE
|RECORD=2|OwnerIndex=331|OwnerPartId=1|FormalType=1|Electrical=4|PinConglomerate=32|PinLength=10|Location.X=1100|Location.Y=810|Name=2|Designator=2|SwapIdPin=2|SwapIDPart=1|PinPropagationDelay=0.000000E+000
|RECORD=2|OwnerIndex=331|OwnerPartId=1|FormalType=1|Electrical=4|PinConglomerate=34|PinLength=10|Location.X=1090|Location.Y=810|Name=1|Designator=1|SwapIdPin=1|SwapIDPart=1|PinPropagationDelay=0.000000E+000
|RECORD=13|OwnerIndex=331|IsNotAccesible=T|IndexInSheet=20|OwnerPartId=1|Location.X=1097|Location.X_Frac=50000|Location.Y=810|Corner.X=1100|Corner.Y=810|LineWidth=1|Color=16711680
|RECORD=13|OwnerIndex=331|IsNotAccesible=T|IndexInSheet=21|OwnerPartId=1|Location.X=1090|Location.Y=810|Corner.X=1092|Corner.X_Frac=50000|Corner.Y=810|LineWidth=1|Color=16711680
|RECORD=13|OwnerIndex=331|IsNotAccesible=T|IndexInSheet=22|OwnerPartId=1|Location.X=1097|Location.X_Frac=50000|Location.Y=815|Corner.X=1097|Corner.X_Frac=50000|Corner.Y=805|LineWidth=1|Color=16711680
|RECORD=13|OwnerIndex=331|IsNotAccesible=T|IndexInSheet=23|OwnerPartId=1|Location.X=1092|Location.X_Frac=50000|Location.Y=815|Corner.X=1092|Corner.X_Frac=50000|Corner.Y=805|LineWidth=1|Color=16711680
|RECORD=41|OwnerIndex=331|IndexInSheet=24|OwnerPartId=-1|Location.X=1078|Location.Y=816|Color=8388608|FontID=1|IsHidden=T|Text=<VALENTIUM>|Name=VALENTIUM PART NUM
|RECORD=34|OwnerIndex=331|IndexInSheet=-1|OwnerPartId=-1|Location.X=1070|Location.Y=796|Color=8388608|FontID=1|Text=C45|Name=Designator|ReadOnlyState=1
|RECORD=41|OwnerIndex=331|IndexInSheet=-1|OwnerPartId=-1|Location.X=1078|Location.Y=816|Color=8388608|FontID=1|IsHidden=T|Text=CAP_0402_0.1UF_50V|Name=Comment|ReadOnlyState=1
|RECORD=44|OwnerIndex=331
|RECORD=45|OwnerIndex=361|IndexInSheet=-1|Description=Chip Capacitor, 0402, 2-Leads, Body 1.00x0.50mm, IPC Medium Density|UseComponentLibrary=T|ModelName=CAPC1005X06N|ModelType=PCBLIB|DatafileCount=1|ModelDatafileEntity0=CAPC1005X06N|ModelDatafileKind0=PCBLib|IsCurrent=T|DatalinksLocked=T|DatabaseDatalinksLocked=T|IntegratedModel=T|DatabaseModel=T
|RECORD=46|OwnerIndex=362
|RECORD=48|OwnerIndex=362
|RECORD=1|LibReference=CAP_0402_0.1UF_50V|ComponentDescription=CAP, CER, 0.1UF, 50V, 10%, X7R, AEC-Q200, 0402|PartCount=2|DisplayModeCount=1|IndexInSheet=42|OwnerPartId=-1|Location.X=1090|Location.Y=800|Orientation=1|CurrentPartId=1|LibraryPath=*|SourceLibraryName=Capacitors.IntLib|TargetFileName=*|AreaColor=11599871|Color=128|PartIDLocked=F|DesignItemId=CAP_0402_0.1UF_50V|AllPinCount=2
|RECORD=41|OwnerIndex=365|OwnerPartId=-1|Location.X=1038|Location.Y=826|Color=8388608|FontID=7|IsHidden=T|Text=CAP, CER|Name=CATEGORY
|RECORD=41|OwnerIndex=365|IndexInSheet=1|OwnerPartId=-1|Location.X=1038|Location.Y=826|Color=8388608|FontID=7|IsHidden=T|Text=TDK|Name=MFG NAME
|RECORD=41|OwnerIndex=365|IndexInSheet=2|OwnerPartId=-1|Location.X=1038|Location.Y=826|Color=8388608|FontID=7|IsHidden=T|Text=CGA2B3X7R1H104K050BB|Name=MFG PART NUM
|RECORD=41|OwnerIndex=365|IndexInSheet=3|OwnerPartId=-1|Location.X=1038|Location.Y=826|Color=8388608|FontID=7|IsHidden=T|Text=10/23/2013|Name=MODIFY DATE
|RECORD=41|OwnerIndex=365|IndexInSheet=4|OwnerPartId=-1|Location.X=1038|Location.Y=826|Color=8388608|FontID=7|IsHidden=T|Name=Date
|RECORD=41|OwnerIndex=365|IndexInSheet=5|OwnerPartId=-1|Location.X=1038|Location.Y=826|Color=8388608|FontID=7|IsHidden=T|Text=*|Name=SHEETPART
|RECORD=41|OwnerIndex=365|IndexInSheet=6|OwnerPartId=-1|Location.X=1038|Location.Y=826|Color=8388608|FontID=7|IsHidden=T|Text=10%|Name=P1
|RECORD=41|OwnerIndex=365|IndexInSheet=7|OwnerPartId=-1|Location.X=1038|Location.Y=826|Color=8388608|FontID=7|IsHidden=T|Text=125C|Name=MAXTEMP
|RECORD=41|OwnerIndex=365|IndexInSheet=8|OwnerPartId=-1|Location.X=1038|Location.Y=826|Color=8388608|FontID=7|IsHidden=T|Text=-55C|Name=MINTEMP
|RECORD=41|OwnerIndex=365|IndexInSheet=9|OwnerPartId=-1|Location.X=1038|Location.Y=826|Color=8388608|FontID=7|IsHidden=T|Text=AEC-Q200|Name=OTHER
|RECORD=41|OwnerIndex=365|IndexInSheet=10|OwnerPartId=-1|Location.X=1038|Location.Y=826|Color=8388608|FontID=7|IsHidden=T|Text=50V|Name=P2
|RECORD=41|OwnerIndex=365|IndexInSheet=11|OwnerPartId=-1|Location.X=1038|Location.Y=826|Color=8388608|FontID=7|IsHidden=T|Text=X7R|Name=P3
|RECORD=41|OwnerIndex=365|IndexInSheet=12|OwnerPartId=-1|Location.X=1038|Location.Y=826|Color=8388608|FontID=7|IsHidden=T|Text=0402|Name=Size
|RECORD=41|OwnerIndex=365|IndexInSheet=13|OwnerPartId=-1|Location.X=1038|Location.Y=826|Color=8388608|FontID=7|IsHidden=T|Name=SUB
|RECORD=41|OwnerIndex=365|IndexInSheet=14|OwnerPartId=-1|Location.X=1038|Location.Y=826|Color=8388608|FontID=1|IsHidden=T|Text=CAP, CER, 0.1UF, 50V, 10%, X7R, AEC-Q200, 0402|Name=DESC
|RECORD=41|OwnerIndex=365|IndexInSheet=15|OwnerPartId=-1|Location.X=1038|Location.Y=826|Color=8388608|FontID=1|IsHidden=T|Text=Digi-Key|Name=Supplier 1|ReadOnlyState=3
|RECORD=41|OwnerIndex=365|IndexInSheet=16|OwnerPartId=-1|Location.X=1038|Location.Y=826|Color=8388608|FontID=1|IsHidden=T|Text=445-6899-1-ND|Name=Supplier Part Number 1|ReadOnlyState=3
|RECORD=41|OwnerIndex=365|IndexInSheet=17|OwnerPartId=-1|Location.X=1060|Location.Y=820|Color=8388608|FontID=7|Text=0.1UF|Name=VALUE
|RECORD=2|OwnerIndex=365|OwnerPartId=1|FormalType=1|Electrical=4|PinConglomerate=32|PinLength=10|Location.X=1060|Location.Y=820|Name=2|Designator=2|SwapIdPin=2|SwapIDPart=1|PinPropagationDelay=0.000000E+000
|RECORD=2|OwnerIndex=365|OwnerPartId=1|FormalType=1|Electrical=4|PinConglomerate=34|PinLength=10|Location.X=1050|Location.Y=820|Name=1|Designator=1|SwapIdPin=1|SwapIDPart=1|PinPropagationDelay=0.000000E+000
|RECORD=13|OwnerIndex=365|IsNotAccesible=T|IndexInSheet=20|OwnerPartId=1|Location.X=1057|Location.X_Frac=50000|Location.Y=820|Corner.X=1060|Corner.Y=820|LineWidth=1|Color=16711680
|RECORD=13|OwnerIndex=365|IsNotAccesible=T|IndexInSheet=21|OwnerPartId=1|Location.X=1050|Location.Y=820|Corner.X=1052|Corner.X_Frac=50000|Corner.Y=820|LineWidth=1|Color=16711680
|RECORD=13|OwnerIndex=365|IsNotAccesible=T|IndexInSheet=22|OwnerPartId=1|Location.X=1057|Location.X_Frac=50000|Location.Y=825|Corner.X=1057|Corner.X_Frac=50000|Corner.Y=815|LineWidth=1|Color=16711680
|RECORD=13|OwnerIndex=365|IsNotAccesible=T|IndexInSheet=23|OwnerPartId=1|Location.X=1052|Location.X_Frac=50000|Location.Y=825|Corner.X=1052|Corner.X_Frac=50000|Corner.Y=815|LineWidth=1|Color=16711680
|RECORD=41|OwnerIndex=365|IndexInSheet=24|OwnerPartId=-1|Location.X=1038|Location.Y=826|Color=8388608|FontID=1|IsHidden=T|Text=<VALENTIUM>|Name=VALENTIUM PART NUM
|RECORD=34|OwnerIndex=365|IndexInSheet=-1|OwnerPartId=-1|Location.X=1030|Location.Y=820|Color=8388608|FontID=1|Text=C44|Name=Designator|ReadOnlyState=1
|RECORD=41|OwnerIndex=365|IndexInSheet=-1|OwnerPartId=-1|Location.X=1038|Location.Y=826|Color=8388608|FontID=1|IsHidden=T|Text=CAP_0402_0.1UF_50V|Name=Comment|ReadOnlyState=1
|RECORD=44|OwnerIndex=365
|RECORD=45|OwnerIndex=395|IndexInSheet=-1|Description=Chip Capacitor, 0402, 2-Leads, Body 1.00x0.50mm, IPC Medium Density|UseComponentLibrary=T|ModelName=CAPC1005X06N|ModelType=PCBLIB|DatafileCount=1|ModelDatafileEntity0=CAPC1005X06N|ModelDatafileKind0=PCBLib|IsCurrent=T|DatalinksLocked=T|DatabaseDatalinksLocked=T|IntegratedModel=T|DatabaseModel=T
|RECORD=46|OwnerIndex=396
|RECORD=48|OwnerIndex=396
|RECORD=1|LibReference=CAP_0402_0.1UF_50V|ComponentDescription=CAP, CER, 0.1UF, 50V, 10%, X7R, AEC-Q200, 0402|PartCount=2|DisplayModeCount=1|IndexInSheet=43|OwnerPartId=-1|Location.X=1060|Location.Y=770|Orientation=1|CurrentPartId=1|LibraryPath=*|SourceLibraryName=Capacitors.IntLib|TargetFileName=*|AreaColor=11599871|Color=128|PartIDLocked=F|DesignItemId=CAP_0402_0.1UF_50V|AllPinCount=2
|RECORD=41|OwnerIndex=399|OwnerPartId=-1|Location.X=1008|Location.Y=796|Color=8388608|FontID=7|IsHidden=T|Text=CAP, CER|Name=CATEGORY
|RECORD=41|OwnerIndex=399|IndexInSheet=1|OwnerPartId=-1|Location.X=1008|Location.Y=796|Color=8388608|FontID=7|IsHidden=T|Text=TDK|Name=MFG NAME
|RECORD=41|OwnerIndex=399|IndexInSheet=2|OwnerPartId=-1|Location.X=1008|Location.Y=796|Color=8388608|FontID=7|IsHidden=T|Text=CGA2B3X7R1H104K050BB|Name=MFG PART NUM
|RECORD=41|OwnerIndex=399|IndexInSheet=3|OwnerPartId=-1|Location.X=1008|Location.Y=796|Color=8388608|FontID=7|IsHidden=T|Text=10/23/2013|Name=MODIFY DATE
|RECORD=41|OwnerIndex=399|IndexInSheet=4|OwnerPartId=-1|Location.X=1008|Location.Y=796|Color=8388608|FontID=7|IsHidden=T|Name=Date
|RECORD=41|OwnerIndex=399|IndexInSheet=5|OwnerPartId=-1|Location.X=1008|Location.Y=796|Color=8388608|FontID=7|IsHidden=T|Text=*|Name=SHEETPART
|RECORD=41|OwnerIndex=399|IndexInSheet=6|OwnerPartId=-1|Location.X=1008|Location.Y=796|Color=8388608|FontID=7|IsHidden=T|Text=10%|Name=P1
|RECORD=41|OwnerIndex=399|IndexInSheet=7|OwnerPartId=-1|Location.X=1008|Location.Y=796|Color=8388608|FontID=7|IsHidden=T|Text=125C|Name=MAXTEMP
|RECORD=41|OwnerIndex=399|IndexInSheet=8|OwnerPartId=-1|Location.X=1008|Location.Y=796|Color=8388608|FontID=7|IsHidden=T|Text=-55C|Name=MINTEMP
|RECORD=41|OwnerIndex=399|IndexInSheet=9|OwnerPartId=-1|Location.X=1008|Location.Y=796|Color=8388608|FontID=7|IsHidden=T|Text=AEC-Q200|Name=OTHER
|RECORD=41|OwnerIndex=399|IndexInSheet=10|OwnerPartId=-1|Location.X=1008|Location.Y=796|Color=8388608|FontID=7|IsHidden=T|Text=50V|Name=P2
|RECORD=41|OwnerIndex=399|IndexInSheet=11|OwnerPartId=-1|Location.X=1008|Location.Y=796|Color=8388608|FontID=7|IsHidden=T|Text=X7R|Name=P3
|RECORD=41|OwnerIndex=399|IndexInSheet=12|OwnerPartId=-1|Location.X=1008|Location.Y=796|Color=8388608|FontID=7|IsHidden=T|Text=0402|Name=Size
|RECORD=41|OwnerIndex=399|IndexInSheet=13|OwnerPartId=-1|Location.X=1008|Location.Y=796|Color=8388608|FontID=7|IsHidden=T|Name=SUB
|RECORD=41|OwnerIndex=399|IndexInSheet=14|OwnerPartId=-1|Location.X=1008|Location.Y=796|Color=8388608|FontID=1|IsHidden=T|Text=CAP, CER, 0.1UF, 50V, 10%, X7R, AEC-Q200, 0402|Name=DESC
|RECORD=41|OwnerIndex=399|IndexInSheet=15|OwnerPartId=-1|Location.X=1008|Location.Y=796|Color=8388608|FontID=1|IsHidden=T|Text=Digi-Key|Name=Supplier 1|ReadOnlyState=3
|RECORD=41|OwnerIndex=399|IndexInSheet=16|OwnerPartId=-1|Location.X=1008|Location.Y=796|Color=8388608|FontID=1|IsHidden=T|Text=445-6899-1-ND|Name=Supplier Part Number 1|ReadOnlyState=3
|RECORD=41|OwnerIndex=399|IndexInSheet=17|OwnerPartId=-1|Location.X=1030|Location.Y=790|Color=8388608|FontID=7|Text=0.1UF|Name=VALUE
|RECORD=2|OwnerIndex=399|OwnerPartId=1|FormalType=1|Electrical=4|PinConglomerate=32|PinLength=10|Location.X=1030|Location.Y=790|Name=2|Designator=2|SwapIdPin=2|SwapIDPart=1|PinPropagationDelay=0.000000E+000
|RECORD=2|OwnerIndex=399|OwnerPartId=1|FormalType=1|Electrical=4|PinConglomerate=34|PinLength=10|Location.X=1020|Location.Y=790|Name=1|Designator=1|SwapIdPin=1|SwapIDPart=1|PinPropagationDelay=0.000000E+000
|RECORD=13|OwnerIndex=399|IsNotAccesible=T|IndexInSheet=20|OwnerPartId=1|Location.X=1027|Location.X_Frac=50000|Location.Y=790|Corner.X=1030|Corner.Y=790|LineWidth=1|Color=16711680
|RECORD=13|OwnerIndex=399|IsNotAccesible=T|IndexInSheet=21|OwnerPartId=1|Location.X=1020|Location.Y=790|Corner.X=1022|Corner.X_Frac=50000|Corner.Y=790|LineWidth=1|Color=16711680
|RECORD=13|OwnerIndex=399|IsNotAccesible=T|IndexInSheet=22|OwnerPartId=1|Location.X=1027|Location.X_Frac=50000|Location.Y=795|Corner.X=1027|Corner.X_Frac=50000|Corner.Y=785|LineWidth=1|Color=16711680
|RECORD=13|OwnerIndex=399|IsNotAccesible=T|IndexInSheet=23|OwnerPartId=1|Location.X=1022|Location.X_Frac=50000|Location.Y=795|Corner.X=1022|Corner.X_Frac=50000|Corner.Y=785|LineWidth=1|Color=16711680
|RECORD=41|OwnerIndex=399|IndexInSheet=24|OwnerPartId=-1|Location.X=1008|Location.Y=796|Color=8388608|FontID=1|IsHidden=T|Text=<VALENTIUM>|Name=VALENTIUM PART NUM
|RECORD=34|OwnerIndex=399|IndexInSheet=-1|OwnerPartId=-1|Location.X=1000|Location.Y=790|Color=8388608|FontID=1|Text=C46|Name=Designator|ReadOnlyState=1
|RECORD=41|OwnerIndex=399|IndexInSheet=-1|OwnerPartId=-1|Location.X=1008|Location.Y=796|Color=8388608|FontID=1|IsHidden=T|Text=CAP_0402_0.1UF_50V|Name=Comment|ReadOnlyState=1
|RECORD=44|OwnerIndex=399
|RECORD=45|OwnerIndex=429|IndexInSheet=-1|Description=Chip Capacitor, 0402, 2-Leads, Body 1.00x0.50mm, IPC Medium Density|UseComponentLibrary=T|ModelName=CAPC1005X06N|ModelType=PCBLIB|DatafileCount=1|ModelDatafileEntity0=CAPC1005X06N|ModelDatafileKind0=PCBLib|IsCurrent=T|DatalinksLocked=T|DatabaseDatalinksLocked=T|IntegratedModel=T|DatabaseModel=T
|RECORD=46|OwnerIndex=430
|RECORD=48|OwnerIndex=430
|RECORD=1|LibReference=CAP_0402_0.1UF_50V|ComponentDescription=CAP, CER, 0.1UF, 50V, 10%, X7R, AEC-Q200, 0402|PartCount=2|DisplayModeCount=1|IndexInSheet=44|OwnerPartId=-1|Location.X=1090|Location.Y=720|Orientation=1|CurrentPartId=1|LibraryPath=*|SourceLibraryName=Capacitors.IntLib|TargetFileName=*|AreaColor=11599871|Color=128|PartIDLocked=F|DesignItemId=CAP_0402_0.1UF_50V|AllPinCount=2
|RECORD=41|OwnerIndex=433|OwnerPartId=-1|Location.X=1038|Location.Y=746|Color=8388608|FontID=7|IsHidden=T|Text=CAP, CER|Name=CATEGORY
|RECORD=41|OwnerIndex=433|IndexInSheet=1|OwnerPartId=-1|Location.X=1038|Location.Y=746|Color=8388608|FontID=7|IsHidden=T|Text=TDK|Name=MFG NAME
|RECORD=41|OwnerIndex=433|IndexInSheet=2|OwnerPartId=-1|Location.X=1038|Location.Y=746|Color=8388608|FontID=7|IsHidden=T|Text=CGA2B3X7R1H104K050BB|Name=MFG PART NUM
|RECORD=41|OwnerIndex=433|IndexInSheet=3|OwnerPartId=-1|Location.X=1038|Location.Y=746|Color=8388608|FontID=7|IsHidden=T|Text=10/23/2013|Name=MODIFY DATE
|RECORD=41|OwnerIndex=433|IndexInSheet=4|OwnerPartId=-1|Location.X=1038|Location.Y=746|Color=8388608|FontID=7|IsHidden=T|Name=Date
|RECORD=41|OwnerIndex=433|IndexInSheet=5|OwnerPartId=-1|Location.X=1038|Location.Y=746|Color=8388608|FontID=7|IsHidden=T|Text=*|Name=SHEETPART
|RECORD=41|OwnerIndex=433|IndexInSheet=6|OwnerPartId=-1|Location.X=1038|Location.Y=746|Color=8388608|FontID=7|IsHidden=T|Text=10%|Name=P1
|RECORD=41|OwnerIndex=433|IndexInSheet=7|OwnerPartId=-1|Location.X=1038|Location.Y=746|Color=8388608|FontID=7|IsHidden=T|Text=125C|Name=MAXTEMP
|RECORD=41|OwnerIndex=433|IndexInSheet=8|OwnerPartId=-1|Location.X=1038|Location.Y=746|Color=8388608|FontID=7|IsHidden=T|Text=-55C|Name=MINTEMP
|RECORD=41|OwnerIndex=433|IndexInSheet=9|OwnerPartId=-1|Location.X=1038|Location.Y=746|Color=8388608|FontID=7|IsHidden=T|Text=AEC-Q200|Name=OTHER
|RECORD=41|OwnerIndex=433|IndexInSheet=10|OwnerPartId=-1|Location.X=1038|Location.Y=746|Color=8388608|FontID=7|IsHidden=T|Text=50V|Name=P2
|RECORD=41|OwnerIndex=433|IndexInSheet=11|OwnerPartId=-1|Location.X=1038|Location.Y=746|Color=8388608|FontID=7|IsHidden=T|Text=X7R|Name=P3
|RECORD=41|OwnerIndex=433|IndexInSheet=12|OwnerPartId=-1|Location.X=1038|Location.Y=746|Color=8388608|FontID=7|IsHidden=T|Text=0402|Name=Size
|RECORD=41|OwnerIndex=433|IndexInSheet=13|OwnerPartId=-1|Location.X=1038|Location.Y=746|Color=8388608|FontID=7|IsHidden=T|Name=SUB
|RECORD=41|OwnerIndex=433|IndexInSheet=14|OwnerPartId=-1|Location.X=1038|Location.Y=746|Color=8388608|FontID=1|IsHidden=T|Text=CAP, CER, 0.1UF, 50V, 10%, X7R, AEC-Q200, 0402|Name=DESC
|RECORD=41|OwnerIndex=433|IndexInSheet=15|OwnerPartId=-1|Location.X=1038|Location.Y=746|Color=8388608|FontID=1|IsHidden=T|Text=Digi-Key|Name=Supplier 1|ReadOnlyState=3
|RECORD=41|OwnerIndex=433|IndexInSheet=16|OwnerPartId=-1|Location.X=1038|Location.Y=746|Color=8388608|FontID=1|IsHidden=T|Text=445-6899-1-ND|Name=Supplier Part Number 1|ReadOnlyState=3
|RECORD=41|OwnerIndex=433|IndexInSheet=17|OwnerPartId=-1|Location.X=1060|Location.Y=740|Color=8388608|FontID=7|Text=0.1UF|Name=VALUE
|RECORD=2|OwnerIndex=433|OwnerPartId=1|FormalType=1|Electrical=4|PinConglomerate=32|PinLength=10|Location.X=1060|Location.Y=740|Name=2|Designator=2|SwapIdPin=2|SwapIDPart=1|PinPropagationDelay=0.000000E+000
|RECORD=2|OwnerIndex=433|OwnerPartId=1|FormalType=1|Electrical=4|PinConglomerate=34|PinLength=10|Location.X=1050|Location.Y=740|Name=1|Designator=1|SwapIdPin=1|SwapIDPart=1|PinPropagationDelay=0.000000E+000
|RECORD=13|OwnerIndex=433|IsNotAccesible=T|IndexInSheet=20|OwnerPartId=1|Location.X=1057|Location.X_Frac=50000|Location.Y=740|Corner.X=1060|Corner.Y=740|LineWidth=1|Color=16711680
|RECORD=13|OwnerIndex=433|IsNotAccesible=T|IndexInSheet=21|OwnerPartId=1|Location.X=1050|Location.Y=740|Corner.X=1052|Corner.X_Frac=50000|Corner.Y=740|LineWidth=1|Color=16711680
|RECORD=13|OwnerIndex=433|IsNotAccesible=T|IndexInSheet=22|OwnerPartId=1|Location.X=1057|Location.X_Frac=50000|Location.Y=745|Corner.X=1057|Corner.X_Frac=50000|Corner.Y=735|LineWidth=1|Color=16711680
|RECORD=13|OwnerIndex=433|IsNotAccesible=T|IndexInSheet=23|OwnerPartId=1|Location.X=1052|Location.X_Frac=50000|Location.Y=745|Corner.X=1052|Corner.X_Frac=50000|Corner.Y=735|LineWidth=1|Color=16711680
|RECORD=41|OwnerIndex=433|IndexInSheet=24|OwnerPartId=-1|Location.X=1038|Location.Y=746|Color=8388608|FontID=1|IsHidden=T|Text=<VALENTIUM>|Name=VALENTIUM PART NUM
|RECORD=34|OwnerIndex=433|IndexInSheet=-1|OwnerPartId=-1|Location.X=1030|Location.Y=740|Color=8388608|FontID=1|Text=C48|Name=Designator|ReadOnlyState=1
|RECORD=41|OwnerIndex=433|IndexInSheet=-1|OwnerPartId=-1|Location.X=1038|Location.Y=746|Color=8388608|FontID=1|IsHidden=T|Text=CAP_0402_0.1UF_50V|Name=Comment|ReadOnlyState=1
|RECORD=44|OwnerIndex=433
|RECORD=45|OwnerIndex=463|IndexInSheet=-1|Description=Chip Capacitor, 0402, 2-Leads, Body 1.00x0.50mm, IPC Medium Density|UseComponentLibrary=T|ModelName=CAPC1005X06N|ModelType=PCBLIB|DatafileCount=1|ModelDatafileEntity0=CAPC1005X06N|ModelDatafileKind0=PCBLib|IsCurrent=T|DatalinksLocked=T|DatabaseDatalinksLocked=T|IntegratedModel=T|DatabaseModel=T
|RECORD=46|OwnerIndex=464
|RECORD=48|OwnerIndex=464
|RECORD=1|LibReference=CAP_0402_0.1UF_50V|ComponentDescription=CAP, CER, 0.1UF, 50V, 10%, X7R, AEC-Q200, 0402|PartCount=2|DisplayModeCount=1|IndexInSheet=45|OwnerPartId=-1|Location.X=1090|Location.Y=680|Orientation=1|CurrentPartId=1|LibraryPath=*|SourceLibraryName=Capacitors.IntLib|TargetFileName=*|AreaColor=11599871|Color=128|PartIDLocked=F|DesignItemId=CAP_0402_0.1UF_50V|AllPinCount=2
|RECORD=41|OwnerIndex=467|OwnerPartId=-1|Location.X=1038|Location.Y=706|Color=8388608|FontID=7|IsHidden=T|Text=CAP, CER|Name=CATEGORY
|RECORD=41|OwnerIndex=467|IndexInSheet=1|OwnerPartId=-1|Location.X=1038|Location.Y=706|Color=8388608|FontID=7|IsHidden=T|Text=TDK|Name=MFG NAME
|RECORD=41|OwnerIndex=467|IndexInSheet=2|OwnerPartId=-1|Location.X=1038|Location.Y=706|Color=8388608|FontID=7|IsHidden=T|Text=CGA2B3X7R1H104K050BB|Name=MFG PART NUM
|RECORD=41|OwnerIndex=467|IndexInSheet=3|OwnerPartId=-1|Location.X=1038|Location.Y=706|Color=8388608|FontID=7|IsHidden=T|Text=10/23/2013|Name=MODIFY DATE
|RECORD=41|OwnerIndex=467|IndexInSheet=4|OwnerPartId=-1|Location.X=1038|Location.Y=706|Color=8388608|FontID=7|IsHidden=T|Name=Date
|RECORD=41|OwnerIndex=467|IndexInSheet=5|OwnerPartId=-1|Location.X=1038|Location.Y=706|Color=8388608|FontID=7|IsHidden=T|Text=*|Name=SHEETPART
|RECORD=41|OwnerIndex=467|IndexInSheet=6|OwnerPartId=-1|Location.X=1038|Location.Y=706|Color=8388608|FontID=7|IsHidden=T|Text=10%|Name=P1
|RECORD=41|OwnerIndex=467|IndexInSheet=7|OwnerPartId=-1|Location.X=1038|Location.Y=706|Color=8388608|FontID=7|IsHidden=T|Text=125C|Name=MAXTEMP
|RECORD=41|OwnerIndex=467|IndexInSheet=8|OwnerPartId=-1|Location.X=1038|Location.Y=706|Color=8388608|FontID=7|IsHidden=T|Text=-55C|Name=MINTEMP
|RECORD=41|OwnerIndex=467|IndexInSheet=9|OwnerPartId=-1|Location.X=1038|Location.Y=706|Color=8388608|FontID=7|IsHidden=T|Text=AEC-Q200|Name=OTHER
|RECORD=41|OwnerIndex=467|IndexInSheet=10|OwnerPartId=-1|Location.X=1038|Location.Y=706|Color=8388608|FontID=7|IsHidden=T|Text=50V|Name=P2
|RECORD=41|OwnerIndex=467|IndexInSheet=11|OwnerPartId=-1|Location.X=1038|Location.Y=706|Color=8388608|FontID=7|IsHidden=T|Text=X7R|Name=P3
|RECORD=41|OwnerIndex=467|IndexInSheet=12|OwnerPartId=-1|Location.X=1038|Location.Y=706|Color=8388608|FontID=7|IsHidden=T|Text=0402|Name=Size
|RECORD=41|OwnerIndex=467|IndexInSheet=13|OwnerPartId=-1|Location.X=1038|Location.Y=706|Color=8388608|FontID=7|IsHidden=T|Name=SUB
|RECORD=41|OwnerIndex=467|IndexInSheet=14|OwnerPartId=-1|Location.X=1038|Location.Y=706|Color=8388608|FontID=1|IsHidden=T|Text=CAP, CER, 0.1UF, 50V, 10%, X7R, AEC-Q200, 0402|Name=DESC
|RECORD=41|OwnerIndex=467|IndexInSheet=15|OwnerPartId=-1|Location.X=1038|Location.Y=706|Color=8388608|FontID=1|IsHidden=T|Text=Digi-Key|Name=Supplier 1|ReadOnlyState=3
|RECORD=41|OwnerIndex=467|IndexInSheet=16|OwnerPartId=-1|Location.X=1038|Location.Y=706|Color=8388608|FontID=1|IsHidden=T|Text=445-6899-1-ND|Name=Supplier Part Number 1|ReadOnlyState=3
|RECORD=41|OwnerIndex=467|IndexInSheet=17|OwnerPartId=-1|Location.X=1060|Location.Y=700|Color=8388608|FontID=7|Text=0.1UF|Name=VALUE
|RECORD=2|OwnerIndex=467|OwnerPartId=1|FormalType=1|Electrical=4|PinConglomerate=32|PinLength=10|Location.X=1060|Location.Y=700|Name=2|Designator=2|SwapIdPin=2|SwapIDPart=1|PinPropagationDelay=0.000000E+000
|RECORD=2|OwnerIndex=467|OwnerPartId=1|FormalType=1|Electrical=4|PinConglomerate=34|PinLength=10|Location.X=1050|Location.Y=700|Name=1|Designator=1|SwapIdPin=1|SwapIDPart=1|PinPropagationDelay=0.000000E+000
|RECORD=13|OwnerIndex=467|IsNotAccesible=T|IndexInSheet=20|OwnerPartId=1|Location.X=1057|Location.X_Frac=50000|Location.Y=700|Corner.X=1060|Corner.Y=700|LineWidth=1|Color=16711680
|RECORD=13|OwnerIndex=467|IsNotAccesible=T|IndexInSheet=21|OwnerPartId=1|Location.X=1050|Location.Y=700|Corner.X=1052|Corner.X_Frac=50000|Corner.Y=700|LineWidth=1|Color=16711680
|RECORD=13|OwnerIndex=467|IsNotAccesible=T|IndexInSheet=22|OwnerPartId=1|Location.X=1057|Location.X_Frac=50000|Location.Y=705|Corner.X=1057|Corner.X_Frac=50000|Corner.Y=695|LineWidth=1|Color=16711680
|RECORD=13|OwnerIndex=467|IsNotAccesible=T|IndexInSheet=23|OwnerPartId=1|Location.X=1052|Location.X_Frac=50000|Location.Y=705|Corner.X=1052|Corner.X_Frac=50000|Corner.Y=695|LineWidth=1|Color=16711680
|RECORD=41|OwnerIndex=467|IndexInSheet=24|OwnerPartId=-1|Location.X=1038|Location.Y=706|Color=8388608|FontID=1|IsHidden=T|Text=<VALENTIUM>|Name=VALENTIUM PART NUM
|RECORD=34|OwnerIndex=467|IndexInSheet=-1|OwnerPartId=-1|Location.X=1030|Location.Y=700|Color=8388608|FontID=1|Text=C50|Name=Designator|ReadOnlyState=1
|RECORD=41|OwnerIndex=467|IndexInSheet=-1|OwnerPartId=-1|Location.X=1038|Location.Y=706|Color=8388608|FontID=1|IsHidden=T|Text=CAP_0402_0.1UF_50V|Name=Comment|ReadOnlyState=1
|RECORD=44|OwnerIndex=467
|RECORD=45|OwnerIndex=497|IndexInSheet=-1|Description=Chip Capacitor, 0402, 2-Leads, Body 1.00x0.50mm, IPC Medium Density|UseComponentLibrary=T|ModelName=CAPC1005X06N|ModelType=PCBLIB|DatafileCount=1|ModelDatafileEntity0=CAPC1005X06N|ModelDatafileKind0=PCBLib|IsCurrent=T|DatalinksLocked=T|DatabaseDatalinksLocked=T|IntegratedModel=T|DatabaseModel=T
|RECORD=46|OwnerIndex=498
|RECORD=48|OwnerIndex=498
|RECORD=1|LibReference=PCIex4|ComponentDescription=PCIE x4 Edge Connector,OrCAD Symbol,NC|PartCount=2|DisplayModeCount=1|IndexInSheet=46|OwnerPartId=-1|Location.X=770|Location.Y=960|CurrentPartId=1|LibraryPath=*|SourceLibraryName=Connectors.IntLib|TargetFileName=*|AreaColor=11599871|Color=128|PartIDLocked=T|DesignItemId=PCIex4|AllPinCount=64
|RECORD=41|OwnerIndex=501|OwnerPartId=1|Location.X=90|Location.Y=150|Color=8388608|FontID=1|IsHidden=T|Text=NC|Name=NOTE|NotAutoPosition=T
|RECORD=41|OwnerIndex=501|IndexInSheet=1|OwnerPartId=1|Location.X=90|Location.Y=150|Color=8388608|FontID=1|IsHidden=T|Text=451|Name=Part Number|NotAutoPosition=T
|RECORD=41|OwnerIndex=501|IndexInSheet=2|OwnerPartId=1|Location.X=90|Location.Y=150|Color=8388608|FontID=1|IsHidden=T|Text=NA|Name=Manufacturer|NotAutoPosition=T
|RECORD=41|OwnerIndex=501|IndexInSheet=3|OwnerPartId=1|Location.X=90|Location.Y=150|Color=8388608|FontID=1|IsHidden=T|Text=NA|Name=Vendor P/N|NotAutoPosition=T
|RECORD=41|OwnerIndex=501|IndexInSheet=4|OwnerPartId=1|Location.X=90|Location.Y=150|Color=8388608|FontID=1|IsHidden=T|Text=SMT|Name=Part Type|NotAutoPosition=T
|RECORD=4|OwnerIndex=501|IsNotAccesible=T|IndexInSheet=5|OwnerPartId=1|Location.X=774|Location.Y=837|Color=8388608|FontID=9|Text=KEY
|RECORD=4|OwnerIndex=501|IsNotAccesible=T|IndexInSheet=6|OwnerPartId=1|Location.X=890|Location.Y=838|Color=8388608|FontID=9|Text=KEY
|RECORD=14|OwnerIndex=501|IsNotAccesible=T|IndexInSheet=7|OwnerPartId=1|Location.X=770|Location.Y=620|Corner.X=910|Corner.Y=960|LineWidth=1|Color=128|AreaColor=11599871|IsSolid=T|Transparent=T
|RECORD=2|OwnerIndex=501|OwnerPartId=1|FormalType=1|Electrical=7|PinConglomerate=58|PinLength=10|Location.X=770|Location.Y=950|Name=+12v1|Designator=B1|SwapIDPart=Ž&Ž||PinPropagationDelay=0.000000E+000
|RECORD=2|OwnerIndex=501|OwnerPartId=1|FormalType=1|Electrical=7|PinConglomerate=58|PinLength=10|Location.X=770|Location.Y=940|Name=+12V2|Designator=B2|SwapIDPart=Ž&Ž||PinPropagationDelay=0.000000E+000
|RECORD=2|OwnerIndex=501|OwnerPartId=1|FormalType=1|Electrical=7|PinConglomerate=58|PinLength=10|Location.X=770|Location.Y=930|Name=+12V3|Designator=B3|SwapIDPart=Ž&Ž||PinPropagationDelay=0.000000E+000
|RECORD=2|OwnerIndex=501|OwnerPartId=1|FormalType=1|Electrical=7|PinConglomerate=58|PinLength=10|Location.X=770|Location.Y=920|Name=GND1|Designator=B4|SwapIDPart=Ž&Ž||PinPropagationDelay=0.000000E+000
|RECORD=2|OwnerIndex=501|OwnerPartId=1|FormalType=1|Electrical=4|PinConglomerate=58|PinLength=10|Location.X=770|Location.Y=910|Name=SMCLK|Designator=B5|SwapIDPart=Ž&Ž||PinPropagationDelay=0.000000E+000
|RECORD=2|OwnerIndex=501|OwnerPartId=1|FormalType=1|Electrical=4|PinConglomerate=58|PinLength=10|Location.X=770|Location.Y=900|Name=SMDATA|Designator=B6|SwapIDPart=Ž&Ž||PinPropagationDelay=0.000000E+000
|RECORD=2|OwnerIndex=501|OwnerPartId=1|FormalType=1|Electrical=7|PinConglomerate=58|PinLength=10|Location.X=770|Location.Y=890|Name=GND2|Designator=B7|SwapIDPart=Ž&Ž||PinPropagationDelay=0.000000E+000
|RECORD=2|OwnerIndex=501|OwnerPartId=1|FormalType=1|Electrical=7|PinConglomerate=58|PinLength=10|Location.X=770|Location.Y=880|Name=+3.3V1|Designator=B8|SwapIDPart=Ž&Ž||PinPropagationDelay=0.000000E+000
|RECORD=2|OwnerIndex=501|OwnerPartId=1|FormalType=1|Electrical=4|PinConglomerate=58|PinLength=10|Location.X=770|Location.Y=870|Name=JTAG/TRST_n|Designator=B9|SwapIDPart=Ž&Ž||PinPropagationDelay=0.000000E+000
|RECORD=2|OwnerIndex=501|OwnerPartId=1|FormalType=1|Electrical=4|PinConglomerate=58|PinLength=10|Location.X=770|Location.Y=860|Name=+3.3vaux|Designator=B10|SwapIDPart=Ž&Ž||PinPropagationDelay=0.000000E+000
|RECORD=2|OwnerIndex=501|OwnerPartId=1|FormalType=1|Electrical=4|PinConglomerate=58|PinLength=10|Location.X=770|Location.Y=850|Name=WAKE_n|Designator=B11|SwapIDPart=Ž&Ž||PinPropagationDelay=0.000000E+000
|RECORD=2|OwnerIndex=501|OwnerPartId=1|FormalType=1|Electrical=4|PinConglomerate=58|PinLength=10|Location.X=770|Location.Y=830|Name=RESERVED1|Designator=B12|SwapIDPart=Ž&Ž||PinPropagationDelay=0.000000E+000
|RECORD=2|OwnerIndex=501|OwnerPartId=1|FormalType=1|Electrical=7|PinConglomerate=58|PinLength=10|Location.X=770|Location.Y=820|Name=GND3|Designator=B13|SwapIDPart=Ž&Ž||PinPropagationDelay=0.000000E+000
|RECORD=2|OwnerIndex=501|OwnerPartId=1|FormalType=1|Electrical=4|PinConglomerate=58|PinLength=10|Location.X=770|Location.Y=810|Name=PETp0|Designator=B14|SwapIDPart=Ž&Ž||PinPropagationDelay=0.000000E+000
|RECORD=2|OwnerIndex=501|OwnerPartId=1|FormalType=1|Electrical=4|PinConglomerate=58|PinLength=10|Location.X=770|Location.Y=800|Name=PETn0|Designator=B15|SwapIDPart=Ž&Ž||PinPropagationDelay=0.000000E+000
|RECORD=2|OwnerIndex=501|OwnerPartId=1|FormalType=1|Electrical=7|PinConglomerate=58|PinLength=10|Location.X=770|Location.Y=790|Name=GND4|Designator=B16|SwapIDPart=Ž&Ž||PinPropagationDelay=0.000000E+000
|RECORD=2|OwnerIndex=501|OwnerPartId=1|FormalType=1|Electrical=4|PinConglomerate=58|PinLength=10|Location.X=770|Location.Y=780|Name=PRSNT2_n|Designator=B17|SwapIDPart=Ž&Ž||PinPropagationDelay=0.000000E+000
|RECORD=2|OwnerIndex=501|OwnerPartId=1|FormalType=1|Electrical=7|PinConglomerate=58|PinLength=10|Location.X=770|Location.Y=770|Name=GND5|Designator=B18|SwapIDPart=Ž&Ž||PinPropagationDelay=0.000000E+000
|RECORD=2|OwnerIndex=501|OwnerPartId=1|FormalType=1|Electrical=4|PinConglomerate=58|PinLength=10|Location.X=770|Location.Y=760|Name=PETp1|Designator=B19|SwapIDPart=Ž&Ž||PinPropagationDelay=0.000000E+000
|RECORD=2|OwnerIndex=501|OwnerPartId=1|FormalType=1|Electrical=4|PinConglomerate=58|PinLength=10|Location.X=770|Location.Y=750|Name=PETn1|Designator=B20|SwapIDPart=Ž&Ž||PinPropagationDelay=0.000000E+000
|RECORD=2|OwnerIndex=501|OwnerPartId=1|FormalType=1|Electrical=7|PinConglomerate=58|PinLength=10|Location.X=770|Location.Y=740|Name=GND6|Designator=B21|SwapIDPart=Ž&Ž||PinPropagationDelay=0.000000E+000
|RECORD=2|OwnerIndex=501|OwnerPartId=1|FormalType=1|Electrical=7|PinConglomerate=58|PinLength=10|Location.X=770|Location.Y=730|Name=GND7|Designator=B22|SwapIDPart=Ž&Ž||PinPropagationDelay=0.000000E+000
|RECORD=2|OwnerIndex=501|OwnerPartId=1|FormalType=1|Electrical=4|PinConglomerate=58|PinLength=10|Location.X=770|Location.Y=720|Name=PETp2|Designator=B23|SwapIDPart=Ž&Ž||PinPropagationDelay=0.000000E+000
|RECORD=2|OwnerIndex=501|OwnerPartId=1|FormalType=1|Electrical=4|PinConglomerate=58|PinLength=10|Location.X=770|Location.Y=710|Name=PETn2|Designator=B24|SwapIDPart=Ž&Ž||PinPropagationDelay=0.000000E+000
|RECORD=2|OwnerIndex=501|OwnerPartId=1|FormalType=1|Electrical=7|PinConglomerate=58|PinLength=10|Location.X=770|Location.Y=700|Name=GND8|Designator=B25|SwapIDPart=Ž&Ž||PinPropagationDelay=0.000000E+000
|RECORD=2|OwnerIndex=501|OwnerPartId=1|FormalType=1|Electrical=7|PinConglomerate=58|PinLength=10|Location.X=770|Location.Y=690|Name=GND9|Designator=B26|SwapIDPart=Ž&Ž||PinPropagationDelay=0.000000E+000
|RECORD=2|OwnerIndex=501|OwnerPartId=1|FormalType=1|Electrical=4|PinConglomerate=58|PinLength=10|Location.X=770|Location.Y=680|Name=PETp3|Designator=B27|SwapIDPart=Ž&Ž||PinPropagationDelay=0.000000E+000
|RECORD=2|OwnerIndex=501|OwnerPartId=1|FormalType=1|Electrical=4|PinConglomerate=58|PinLength=10|Location.X=770|Location.Y=670|Name=PETn3|Designator=B28|SwapIDPart=Ž&Ž||PinPropagationDelay=0.000000E+000
|RECORD=2|OwnerIndex=501|OwnerPartId=1|FormalType=1|Electrical=7|PinConglomerate=58|PinLength=10|Location.X=770|Location.Y=660|Name=GND10|Designator=B29|SwapIDPart=Ž&Ž||PinPropagationDelay=0.000000E+000
|RECORD=2|OwnerIndex=501|OwnerPartId=1|FormalType=1|Electrical=4|PinConglomerate=58|PinLength=10|Location.X=770|Location.Y=650|Name=RESERVED2|Designator=B30|SwapIDPart=Ž&Ž||PinPropagationDelay=0.000000E+000
|RECORD=2|OwnerIndex=501|OwnerPartId=1|FormalType=1|Electrical=4|PinConglomerate=58|PinLength=10|Location.X=770|Location.Y=640|Name=PRSNT4_n|Designator=B31|SwapIDPart=Ž&Ž||PinPropagationDelay=0.000000E+000
|RECORD=2|OwnerIndex=501|OwnerPartId=1|FormalType=1|Electrical=7|PinConglomerate=58|PinLength=10|Location.X=770|Location.Y=630|Name=GND11|Designator=B32|SwapIDPart=Ž&Ž||PinPropagationDelay=0.000000E+000
|RECORD=2|OwnerIndex=501|OwnerPartId=1|FormalType=1|Electrical=4|PinConglomerate=56|PinLength=10|Location.X=910|Location.Y=950|Name=PRSNT1_n|Designator=A1|SwapIDPart=Ž&Ž||PinPropagationDelay=0.000000E+000
|RECORD=2|OwnerIndex=501|OwnerPartId=1|FormalType=1|Electrical=4|PinConglomerate=56|PinLength=10|Location.X=910|Location.Y=940|Name=+12V5|Designator=A2|SwapIDPart=Ž&Ž||PinPropagationDelay=0.000000E+000
|RECORD=2|OwnerIndex=501|OwnerPartId=1|FormalType=1|Electrical=4|PinConglomerate=56|PinLength=10|Location.X=910|Location.Y=930|Name=+12V4|Designator=A3|SwapIDPart=Ž&Ž||PinPropagationDelay=0.000000E+000
|RECORD=2|OwnerIndex=501|OwnerPartId=1|FormalType=1|Electrical=7|PinConglomerate=56|PinLength=10|Location.X=910|Location.Y=920|Name=GND37|Designator=A4|SwapIDPart=Ž&Ž||PinPropagationDelay=0.000000E+000
|RECORD=2|OwnerIndex=501|OwnerPartId=1|FormalType=1|Electrical=4|PinConglomerate=56|PinLength=10|Location.X=910|Location.Y=910|Name=JTAG/TCK|Designator=A5|SwapIDPart=Ž&Ž||PinPropagationDelay=0.000000E+000
|RECORD=2|OwnerIndex=501|OwnerPartId=1|FormalType=1|Electrical=4|PinConglomerate=56|PinLength=10|Location.X=910|Location.Y=900|Name=JTAG/TDI|Designator=A6|SwapIDPart=Ž&Ž||PinPropagationDelay=0.000000E+000
|RECORD=2|OwnerIndex=501|OwnerPartId=1|FormalType=1|Electrical=4|PinConglomerate=56|PinLength=10|Location.X=910|Location.Y=890|Name=JTAG/TDO|Designator=A7|SwapIDPart=Ž&Ž||PinPropagationDelay=0.000000E+000
|RECORD=2|OwnerIndex=501|OwnerPartId=1|FormalType=1|Electrical=4|PinConglomerate=56|PinLength=10|Location.X=910|Location.Y=880|Name=JTAG/TMS|Designator=A8|SwapIDPart=Ž&Ž||PinPropagationDelay=0.000000E+000
|RECORD=2|OwnerIndex=501|OwnerPartId=1|FormalType=1|Electrical=4|PinConglomerate=56|PinLength=10|Location.X=910|Location.Y=870|Name=+3.3V3|Designator=A9|SwapIDPart=Ž&Ž||PinPropagationDelay=0.000000E+000
|RECORD=2|OwnerIndex=501|OwnerPartId=1|FormalType=1|Electrical=4|PinConglomerate=56|PinLength=10|Location.X=910|Location.Y=860|Name=+3.3V2|Designator=A10|SwapIDPart=Ž&Ž||PinPropagationDelay=0.000000E+000
|RECORD=2|OwnerIndex=501|OwnerPartId=1|FormalType=1|Electrical=4|PinConglomerate=56|PinLength=10|Location.X=910|Location.Y=850|Name=PERST|Designator=A11|SwapIDPart=Ž&Ž||PinPropagationDelay=0.000000E+000
|RECORD=2|OwnerIndex=501|OwnerPartId=1|FormalType=1|Electrical=7|PinConglomerate=56|PinLength=10|Location.X=910|Location.Y=830|Name=GND36|Designator=A12|SwapIDPart=Ž&Ž||PinPropagationDelay=0.000000E+000
|RECORD=2|OwnerIndex=501|OwnerPartId=1|FormalType=1|Electrical=4|PinConglomerate=56|PinLength=10|Location.X=910|Location.Y=820|Name=REFCLK+|Designator=A13|SwapIDPart=Ž&Ž||PinPropagationDelay=0.000000E+000
|RECORD=2|OwnerIndex=501|OwnerPartId=1|FormalType=1|Electrical=4|PinConglomerate=56|PinLength=10|Location.X=910|Location.Y=810|Name=REFCLK-|Designator=A14|SwapIDPart=Ž&Ž||PinPropagationDelay=0.000000E+000
|RECORD=2|OwnerIndex=501|OwnerPartId=1|FormalType=1|Electrical=7|PinConglomerate=56|PinLength=10|Location.X=910|Location.Y=800|Name=GND35|Designator=A15|SwapIDPart=Ž&Ž||PinPropagationDelay=0.000000E+000
|RECORD=2|OwnerIndex=501|OwnerPartId=1|FormalType=1|Electrical=4|PinConglomerate=56|PinLength=10|Location.X=910|Location.Y=790|Name=PERp0|Designator=A16|SwapIDPart=Ž&Ž||PinPropagationDelay=0.000000E+000
|RECORD=2|OwnerIndex=501|OwnerPartId=1|FormalType=1|Electrical=4|PinConglomerate=56|PinLength=10|Location.X=910|Location.Y=780|Name=PERn0|Designator=A17|SwapIDPart=Ž&Ž||PinPropagationDelay=0.000000E+000
|RECORD=2|OwnerIndex=501|OwnerPartId=1|FormalType=1|Electrical=7|PinConglomerate=56|PinLength=10|Location.X=910|Location.Y=770|Name=GND34|Designator=A18|SwapIDPart=Ž&Ž||PinPropagationDelay=0.000000E+000
|RECORD=2|OwnerIndex=501|OwnerPartId=1|FormalType=1|Electrical=4|PinConglomerate=56|PinLength=10|Location.X=910|Location.Y=760|Name=RESERVED5|Designator=A19|SwapIDPart=Ž&Ž||PinPropagationDelay=0.000000E+000
|RECORD=2|OwnerIndex=501|OwnerPartId=1|FormalType=1|Electrical=7|PinConglomerate=56|PinLength=10|Location.X=910|Location.Y=750|Name=GND33|Designator=A20|SwapIDPart=Ž&Ž||PinPropagationDelay=0.000000E+000
|RECORD=2|OwnerIndex=501|OwnerPartId=1|FormalType=1|Electrical=4|PinConglomerate=56|PinLength=10|Location.X=910|Location.Y=740|Name=PERp1|Designator=A21|SwapIDPart=Ž&Ž||PinPropagationDelay=0.000000E+000
|RECORD=2|OwnerIndex=501|OwnerPartId=1|FormalType=1|Electrical=4|PinConglomerate=56|PinLength=10|Location.X=910|Location.Y=730|Name=PERn1|Designator=A22|SwapIDPart=Ž&Ž||PinPropagationDelay=0.000000E+000
|RECORD=2|OwnerIndex=501|OwnerPartId=1|FormalType=1|Electrical=7|PinConglomerate=56|PinLength=10|Location.X=910|Location.Y=720|Name=GND32|Designator=A23|SwapIDPart=Ž&Ž||PinPropagationDelay=0.000000E+000
|RECORD=2|OwnerIndex=501|OwnerPartId=1|FormalType=1|Electrical=7|PinConglomerate=56|PinLength=10|Location.X=910|Location.Y=710|Name=GND31|Designator=A24|SwapIDPart=Ž&Ž||PinPropagationDelay=0.000000E+000
|RECORD=2|OwnerIndex=501|OwnerPartId=1|FormalType=1|Electrical=4|PinConglomerate=56|PinLength=10|Location.X=910|Location.Y=700|Name=PERp2|Designator=A25|SwapIDPart=Ž&Ž||PinPropagationDelay=0.000000E+000
|RECORD=2|OwnerIndex=501|OwnerPartId=1|FormalType=1|Electrical=4|PinConglomerate=56|PinLength=10|Location.X=910|Location.Y=690|Name=PERn2|Designator=A26|SwapIDPart=Ž&Ž||PinPropagationDelay=0.000000E+000
|RECORD=2|OwnerIndex=501|OwnerPartId=1|FormalType=1|Electrical=7|PinConglomerate=56|PinLength=10|Location.X=910|Location.Y=680|Name=GND30|Designator=A27|SwapIDPart=Ž&Ž||PinPropagationDelay=0.000000E+000
|RECORD=2|OwnerIndex=501|OwnerPartId=1|FormalType=1|Electrical=7|PinConglomerate=56|PinLength=10|Location.X=910|Location.Y=670|Name=GND29|Designator=A28|SwapIDPart=Ž&Ž||PinPropagationDelay=0.000000E+000
|RECORD=2|OwnerIndex=501|OwnerPartId=1|FormalType=1|Electrical=4|PinConglomerate=56|PinLength=10|Location.X=910|Location.Y=660|Name=PERp3|Designator=A29|SwapIDPart=Ž&Ž||PinPropagationDelay=0.000000E+000
|RECORD=2|OwnerIndex=501|OwnerPartId=1|FormalType=1|Electrical=4|PinConglomerate=56|PinLength=10|Location.X=910|Location.Y=650|Name=PERn3|Designator=A30|SwapIDPart=Ž&Ž||PinPropagationDelay=0.000000E+000
|RECORD=2|OwnerIndex=501|OwnerPartId=1|FormalType=1|Electrical=7|PinConglomerate=56|PinLength=10|Location.X=910|Location.Y=640|Name=GND28|Designator=A31|SwapIDPart=Ž&Ž||PinPropagationDelay=0.000000E+000
|RECORD=2|OwnerIndex=501|OwnerPartId=1|FormalType=1|Electrical=4|PinConglomerate=56|PinLength=10|Location.X=910|Location.Y=630|Name=RESERVED4|Designator=A32|SwapIDPart=Ž&Ž||PinPropagationDelay=0.000000E+000
|RECORD=34|OwnerIndex=501|IndexInSheet=-1|OwnerPartId=1|Location.X=770|Location.Y=963|Color=8388608|FontID=8|Text=P2|Name=Designator|ReadOnlyState=1|OverrideNotAutoPosition=T
|RECORD=41|OwnerIndex=501|IndexInSheet=-1|OwnerPartId=-1|Location.X=882|Location.Y=609|Color=8388608|FontID=1|Text=PCIex4|Name=Comment|NotAutoPosition=T
|RECORD=44|OwnerIndex=501
|RECORD=45|OwnerIndex=640|IndexInSheet=-1|Description=PCIE_4LANE_EDGE|UseComponentLibrary=T|ModelName=PCIE_4LANE_EDGE|ModelType=PCBLIB|DatafileCount=1|ModelDatafileEntity0=PCIE_4LANE_EDGE|ModelDatafileKind0=PCBLib|IsCurrent=T|DatalinksLocked=T|DatabaseDatalinksLocked=T|IntegratedModel=T|DatabaseModel=T
|RECORD=46|OwnerIndex=641
|RECORD=48|OwnerIndex=641
|RECORD=45|OwnerIndex=640|IndexInSheet=-1|ModelName=ALINX_FPGA|ModelType=PCBLIB|DatafileCount=1|ModelDatafileEntity0=ALINX_FPGA|ModelDatafileKind0=PCBLib|IntegratedModel=T|DatabaseModel=T
|RECORD=46|OwnerIndex=644
|RECORD=48|OwnerIndex=644
|RECORD=17|IndexInSheet=47|OwnerPartId=-1|Style=4|ShowNetName=T|Location.X=1010|Location.Y=330|Orientation=3|Color=128|FontID=1|Text=GND
|RECORD=22|IndexInSheet=48|OwnerPartId=-1|Location.X=980|Location.Y=360|Color=255|Orientation=1|Symbol=Thin Cross|IsActive=T|SuppressAll=T
|RECORD=22|IndexInSheet=49|OwnerPartId=-1|Location.X=880|Location.Y=360|Color=255|Orientation=1|Symbol=Thin Cross|IsActive=T|SuppressAll=T
|RECORD=17|IndexInSheet=50|OwnerPartId=-1|ShowNetName=T|Location.X=1030|Location.Y=410|Orientation=1|Color=128|FontID=1|Text=+3.3V
|RECORD=17|IndexInSheet=51|OwnerPartId=-1|Style=4|ShowNetName=T|Location.X=590|Location.Y=180|Orientation=3|Color=128|FontID=1|Text=GND
|RECORD=17|IndexInSheet=52|OwnerPartId=-1|Style=4|ShowNetName=T|Location.X=730|Location.Y=180|Orientation=3|Color=128|FontID=1|Text=GND
|RECORD=17|IndexInSheet=53|OwnerPartId=-1|Style=4|ShowNetName=T|Location.X=870|Location.Y=180|Orientation=3|Color=128|FontID=1|Text=GND
|RECORD=17|IndexInSheet=54|OwnerPartId=-1|Style=4|ShowNetName=T|Location.X=1010|Location.Y=180|Orientation=3|Color=128|FontID=1|Text=GND
|RECORD=17|IndexInSheet=55|OwnerPartId=-1|ShowNetName=T|Location.X=630|Location.Y=170|Orientation=3|Color=128|FontID=1|Text=+3.3V
|RECORD=17|IndexInSheet=56|OwnerPartId=-1|ShowNetName=T|Location.X=770|Location.Y=169|Orientation=3|Color=128|FontID=1|Text=+3.3V
|RECORD=17|IndexInSheet=57|OwnerPartId=-1|ShowNetName=T|Location.X=910|Location.Y=170|Orientation=3|Color=128|FontID=1|Text=+3.3V
|RECORD=17|IndexInSheet=58|OwnerPartId=-1|ShowNetName=T|Location.X=1050|Location.Y=170|Orientation=3|Color=128|FontID=1|Text=+3.3V
|RECORD=17|IndexInSheet=59|OwnerPartId=-1|ShowNetName=T|Location.X=730|Location.Y=430|Orientation=2|Color=255|FontID=1|Text=FPGA_TCK|IsCrossSheetConnector=T
|RECORD=41|OwnerIndex=659|OwnerPartId=-1|Location.X=668|Location.X_Frac=26367|Location.Y=430|Orientation=2|Justification=3|Color=8388608|FontID=1|Text=FPGA[2D], PCIe_JTAG[3D]|Name=CrossRef|ReadOnlyState=3
|RECORD=17|IndexInSheet=60|OwnerPartId=-1|ShowNetName=T|Location.X=730|Location.Y=400|Orientation=2|Color=255|FontID=1|Text=FPGA_TDO|IsCrossSheetConnector=T
|RECORD=41|OwnerIndex=661|OwnerPartId=-1|Location.X=668|Location.X_Frac=18872|Location.Y=400|Orientation=2|Justification=3|Color=8388608|FontID=1|Text=FPGA[2D], PCIe_JTAG[3D]|Name=CrossRef|ReadOnlyState=3
|RECORD=17|IndexInSheet=61|OwnerPartId=-1|ShowNetName=T|Location.X=730|Location.Y=370|Orientation=2|Color=255|FontID=1|Text=FPGA_TMS|IsCrossSheetConnector=T
|RECORD=41|OwnerIndex=663|OwnerPartId=-1|Location.X=668|Location.X_Frac=31658|Location.Y=370|Orientation=2|Justification=3|Color=8388608|FontID=1|Text=FPGA[3D], PCIe_JTAG[4D]|Name=CrossRef|ReadOnlyState=3
|RECORD=17|IndexInSheet=62|OwnerPartId=-1|ShowNetName=T|Location.X=730|Location.Y=340|Orientation=2|Color=255|FontID=1|Text=FPGA_TDI|IsCrossSheetConnector=T
|RECORD=41|OwnerIndex=665|OwnerPartId=-1|Location.X=671|Location.X_Frac=57496|Location.Y=340|Orientation=2|Justification=3|Color=8388608|FontID=1|Text=FPGA[3D], PCIe_JTAG[4D]|Name=CrossRef|ReadOnlyState=3
|RECORD=4|IndexInSheet=63|OwnerPartId=-1|Location.X=910|Location.Y=430|Color=8388608|FontID=6|Text=JTAG
|RECORD=1|LibReference=RES_0805_33|ComponentDescription=RES, 33 OHM, 1%, 1/8W, TF, 0805|PartCount=2|DisplayModeCount=1|IndexInSheet=64|OwnerPartId=-1|Location.X=790|Location.Y=430|CurrentPartId=1|LibraryPath=*|SourceLibraryName=Resistors.IntLib|TargetFileName=*|AreaColor=11599871|Color=128|PartIDLocked=F|DesignItemId=RES_0805_33|AllPinCount=2
|RECORD=41|OwnerIndex=668|OwnerPartId=-1|Location.X=790|Location.Y=430|Color=8388608|FontID=7|IsHidden=T|Text=CRCW080533R0FKEA|Name=MFG PART NUM
|RECORD=41|OwnerIndex=668|IndexInSheet=1|OwnerPartId=-1|Location.X=790|Location.Y=430|Color=8388608|FontID=7|IsHidden=T|Text=VISHAY/DALE|Name=MFG NAME
|RECORD=41|OwnerIndex=668|IndexInSheet=2|OwnerPartId=-1|Location.X=790|Location.Y=430|Color=8388608|FontID=7|IsHidden=T|Text=RES|Name=CATEGORY
|RECORD=41|OwnerIndex=668|IndexInSheet=3|OwnerPartId=-1|Location.X=790|Location.Y=430|Color=8388608|FontID=7|IsHidden=T|Text=7/26/2013|Name=ModifyDate
|RECORD=41|OwnerIndex=668|IndexInSheet=4|OwnerPartId=-1|Location.X=788|Location.Y=440|Color=8388608|FontID=7|IsHidden=T|Name=Date
|RECORD=41|OwnerIndex=668|IndexInSheet=5|OwnerPartId=-1|Location.X=778|Location.X_Frac=55769|Location.Y=440|Color=8388608|FontID=7|IsHidden=T|Text=1%|Name=P1
|RECORD=41|OwnerIndex=668|IndexInSheet=6|OwnerPartId=-1|Location.X=778|Location.X_Frac=55769|Location.Y=440|Color=8388608|FontID=7|IsHidden=T|Text=TF|Name=P3
|RECORD=41|OwnerIndex=668|IndexInSheet=7|OwnerPartId=-1|Location.X=778|Location.X_Frac=55769|Location.Y=440|Color=8388608|FontID=7|IsHidden=T|Text=1/8W|Name=P2
|RECORD=41|OwnerIndex=668|IndexInSheet=8|OwnerPartId=-1|Location.X=778|Location.X_Frac=55769|Location.Y=440|Color=8388608|FontID=7|IsHidden=T|Text=125C|Name=MAXTEMP
|RECORD=41|OwnerIndex=668|IndexInSheet=9|OwnerPartId=-1|Location.X=778|Location.X_Frac=55769|Location.Y=440|Color=8388608|FontID=7|IsHidden=T|Text=-55C|Name=MINTEMP
|RECORD=41|OwnerIndex=668|IndexInSheet=10|OwnerPartId=-1|Location.X=778|Location.X_Frac=55769|Location.Y=440|Color=8388608|FontID=7|IsHidden=T|Text=100PPM|Name=OTHER
|RECORD=41|OwnerIndex=668|IndexInSheet=11|OwnerPartId=-1|Location.X=778|Location.X_Frac=55769|Location.Y=440|Color=8388608|FontID=7|IsHidden=T|Text=0805|Name=SIZE
|RECORD=41|OwnerIndex=668|IndexInSheet=12|OwnerPartId=-1|Location.X=778|Location.X_Frac=55769|Location.Y=440|Color=8388608|FontID=7|IsHidden=T|Name=SUB
|RECORD=41|OwnerIndex=668|IndexInSheet=13|OwnerPartId=-1|Location.X=778|Location.X_Frac=55769|Location.Y=440|Color=8388608|FontID=7|IsHidden=T|Text=Digi-Key|Name=Supplier 1|ReadOnlyState=3
|RECORD=41|OwnerIndex=668|IndexInSheet=14|OwnerPartId=-1|Location.X=778|Location.X_Frac=55769|Location.Y=440|Color=8388608|FontID=7|IsHidden=T|Text=541-33.0CCT-ND|Name=Supplier Part Number 1|ReadOnlyState=3
|RECORD=41|OwnerIndex=668|IndexInSheet=15|OwnerPartId=-1|Location.X=773|Location.X_Frac=98077|Location.Y=416|Color=8388608|FontID=1|IsHidden=T|Text=*|Name=SHEETPART
|RECORD=41|OwnerIndex=668|IndexInSheet=16|OwnerPartId=-1|Location.X=773|Location.X_Frac=98077|Location.Y=444|Color=8388608|FontID=1|IsHidden=T|Text=RES, 33 OHM, 1%, 1/8W, TF, 0805|Name=DESC
|RECORD=41|OwnerIndex=668|IndexInSheet=17|OwnerPartId=-1|Location.X=799|Location.Y=414|Color=8388608|FontID=7|Text=33 OHM|Name=VALUE
|RECORD=2|OwnerIndex=668|OwnerPartId=1|FormalType=1|Electrical=4|PinConglomerate=34|PinLength=10|Location.X=800|Location.Y=430|Name=1|Designator=1|PinPropagationDelay=0.000000E+000
|RECORD=2|OwnerIndex=668|OwnerPartId=1|FormalType=1|Electrical=4|PinConglomerate=32|PinLength=10|Location.X=830|Location.Y=430|Name=2|Designator=2|PinPropagationDelay=0.000000E+000
|RECORD=6|OwnerIndex=668|IsNotAccesible=T|IndexInSheet=20|OwnerPartId=1|LineWidth=1|Color=16711680|LocationCount=7|X1=830|Y1=430|X2=827|Y2=433|X3=821|Y3=427|X4=815|Y4=433|X5=809|Y5=427|X6=803|Y6=433|X7=800|Y7=430
|RECORD=41|OwnerIndex=668|IndexInSheet=21|OwnerPartId=-1|Location.X=774|Location.X_Frac=61102|Location.Y=444|Color=8388608|FontID=1|IsHidden=T|Text=<VELENTIUM>|Name=VELENTIUM PART NUM
|RECORD=34|OwnerIndex=668|IndexInSheet=-1|OwnerPartId=-1|Location.X=799|Location.Y=434|Color=8388608|FontID=1|Text=R18|Name=Designator|ReadOnlyState=1
|RECORD=41|OwnerIndex=668|IndexInSheet=-1|OwnerPartId=-1|Location.X=810|Location.Y=420|Color=8388608|FontID=1|IsHidden=T|Text==MFG PART NUM|Name=Comment
|RECORD=44|OwnerIndex=668
|RECORD=45|OwnerIndex=695|IndexInSheet=-1|Description=Chip Resistor, 0805, 2-Leads, Body 2.05x1.25mm, IPC Medium Density|UseComponentLibrary=T|ModelName=RESC2012X50N|ModelType=PCBLIB|DatafileCount=1|ModelDatafileEntity0=RESC2012X50N|ModelDatafileKind0=PCBLib|IsCurrent=T|DatalinksLocked=T|DatabaseDatalinksLocked=T|IntegratedModel=T|DatabaseModel=T
|RECORD=46|OwnerIndex=696
|RECORD=48|OwnerIndex=696
|RECORD=1|LibReference=RES_0805_33|ComponentDescription=RES, 33 OHM, 1%, 1/8W, TF, 0805|PartCount=2|DisplayModeCount=1|IndexInSheet=65|OwnerPartId=-1|Location.X=790|Location.Y=400|CurrentPartId=1|LibraryPath=*|SourceLibraryName=Resistors.IntLib|TargetFileName=*|AreaColor=11599871|Color=128|PartIDLocked=F|DesignItemId=RES_0805_33|AllPinCount=2
|RECORD=41|OwnerIndex=699|OwnerPartId=-1|Location.X=790|Location.Y=400|Color=8388608|FontID=7|IsHidden=T|Text=CRCW080533R0FKEA|Name=MFG PART NUM
|RECORD=41|OwnerIndex=699|IndexInSheet=1|OwnerPartId=-1|Location.X=790|Location.Y=400|Color=8388608|FontID=7|IsHidden=T|Text=VISHAY/DALE|Name=MFG NAME
|RECORD=41|OwnerIndex=699|IndexInSheet=2|OwnerPartId=-1|Location.X=790|Location.Y=400|Color=8388608|FontID=7|IsHidden=T|Text=RES|Name=CATEGORY
|RECORD=41|OwnerIndex=699|IndexInSheet=3|OwnerPartId=-1|Location.X=790|Location.Y=400|Color=8388608|FontID=7|IsHidden=T|Text=7/26/2013|Name=ModifyDate
|RECORD=41|OwnerIndex=699|IndexInSheet=4|OwnerPartId=-1|Location.X=788|Location.Y=410|Color=8388608|FontID=7|IsHidden=T|Name=Date
|RECORD=41|OwnerIndex=699|IndexInSheet=5|OwnerPartId=-1|Location.X=778|Location.X_Frac=55769|Location.Y=410|Color=8388608|FontID=7|IsHidden=T|Text=1%|Name=P1
|RECORD=41|OwnerIndex=699|IndexInSheet=6|OwnerPartId=-1|Location.X=778|Location.X_Frac=55769|Location.Y=410|Color=8388608|FontID=7|IsHidden=T|Text=TF|Name=P3
|RECORD=41|OwnerIndex=699|IndexInSheet=7|OwnerPartId=-1|Location.X=778|Location.X_Frac=55769|Location.Y=410|Color=8388608|FontID=7|IsHidden=T|Text=1/8W|Name=P2
|RECORD=41|OwnerIndex=699|IndexInSheet=8|OwnerPartId=-1|Location.X=778|Location.X_Frac=55769|Location.Y=410|Color=8388608|FontID=7|IsHidden=T|Text=125C|Name=MAXTEMP
|RECORD=41|OwnerIndex=699|IndexInSheet=9|OwnerPartId=-1|Location.X=778|Location.X_Frac=55769|Location.Y=410|Color=8388608|FontID=7|IsHidden=T|Text=-55C|Name=MINTEMP
|RECORD=41|OwnerIndex=699|IndexInSheet=10|OwnerPartId=-1|Location.X=778|Location.X_Frac=55769|Location.Y=410|Color=8388608|FontID=7|IsHidden=T|Text=100PPM|Name=OTHER
|RECORD=41|OwnerIndex=699|IndexInSheet=11|OwnerPartId=-1|Location.X=778|Location.X_Frac=55769|Location.Y=410|Color=8388608|FontID=7|IsHidden=T|Text=0805|Name=SIZE
|RECORD=41|OwnerIndex=699|IndexInSheet=12|OwnerPartId=-1|Location.X=778|Location.X_Frac=55769|Location.Y=410|Color=8388608|FontID=7|IsHidden=T|Name=SUB
|RECORD=41|OwnerIndex=699|IndexInSheet=13|OwnerPartId=-1|Location.X=778|Location.X_Frac=55769|Location.Y=410|Color=8388608|FontID=7|IsHidden=T|Text=Digi-Key|Name=Supplier 1|ReadOnlyState=3
|RECORD=41|OwnerIndex=699|IndexInSheet=14|OwnerPartId=-1|Location.X=778|Location.X_Frac=55769|Location.Y=410|Color=8388608|FontID=7|IsHidden=T|Text=541-33.0CCT-ND|Name=Supplier Part Number 1|ReadOnlyState=3
|RECORD=41|OwnerIndex=699|IndexInSheet=15|OwnerPartId=-1|Location.X=773|Location.X_Frac=98077|Location.Y=386|Color=8388608|FontID=1|IsHidden=T|Text=*|Name=SHEETPART
|RECORD=41|OwnerIndex=699|IndexInSheet=16|OwnerPartId=-1|Location.X=773|Location.X_Frac=98077|Location.Y=414|Color=8388608|FontID=1|IsHidden=T|Text=RES, 33 OHM, 1%, 1/8W, TF, 0805|Name=DESC
|RECORD=41|OwnerIndex=699|IndexInSheet=17|OwnerPartId=-1|Location.X=799|Location.Y=384|Color=8388608|FontID=7|Text=33 OHM|Name=VALUE
|RECORD=2|OwnerIndex=699|OwnerPartId=1|FormalType=1|Electrical=4|PinConglomerate=34|PinLength=10|Location.X=800|Location.Y=400|Name=1|Designator=1|PinPropagationDelay=0.000000E+000
|RECORD=2|OwnerIndex=699|OwnerPartId=1|FormalType=1|Electrical=4|PinConglomerate=32|PinLength=10|Location.X=830|Location.Y=400|Name=2|Designator=2|PinPropagationDelay=0.000000E+000
|RECORD=6|OwnerIndex=699|IsNotAccesible=T|IndexInSheet=20|OwnerPartId=1|LineWidth=1|Color=16711680|LocationCount=7|X1=830|Y1=400|X2=827|Y2=403|X3=821|Y3=397|X4=815|Y4=403|X5=809|Y5=397|X6=803|Y6=403|X7=800|Y7=400
|RECORD=41|OwnerIndex=699|IndexInSheet=21|OwnerPartId=-1|Location.X=774|Location.X_Frac=61102|Location.Y=414|Color=8388608|FontID=1|IsHidden=T|Text=<VELENTIUM>|Name=VELENTIUM PART NUM
|RECORD=34|OwnerIndex=699|IndexInSheet=-1|OwnerPartId=-1|Location.X=799|Location.Y=404|Color=8388608|FontID=1|Text=R19|Name=Designator|ReadOnlyState=1
|RECORD=41|OwnerIndex=699|IndexInSheet=-1|OwnerPartId=-1|Location.X=810|Location.Y=390|Color=8388608|FontID=1|IsHidden=T|Text==MFG PART NUM|Name=Comment
|RECORD=44|OwnerIndex=699
|RECORD=45|OwnerIndex=726|IndexInSheet=-1|Description=Chip Resistor, 0805, 2-Leads, Body 2.05x1.25mm, IPC Medium Density|UseComponentLibrary=T|ModelName=RESC2012X50N|ModelType=PCBLIB|DatafileCount=1|ModelDatafileEntity0=RESC2012X50N|ModelDatafileKind0=PCBLib|IsCurrent=T|DatalinksLocked=T|DatabaseDatalinksLocked=T|IntegratedModel=T|DatabaseModel=T
|RECORD=46|OwnerIndex=727
|RECORD=48|OwnerIndex=727
|RECORD=1|LibReference=RES_0805_33|ComponentDescription=RES, 33 OHM, 1%, 1/8W, TF, 0805|PartCount=2|DisplayModeCount=1|IndexInSheet=66|OwnerPartId=-1|Location.X=790|Location.Y=370|CurrentPartId=1|LibraryPath=*|SourceLibraryName=Resistors.IntLib|TargetFileName=*|AreaColor=11599871|Color=128|PartIDLocked=F|DesignItemId=RES_0805_33|AllPinCount=2
|RECORD=41|OwnerIndex=730|OwnerPartId=-1|Location.X=790|Location.Y=370|Color=8388608|FontID=7|IsHidden=T|Text=CRCW080533R0FKEA|Name=MFG PART NUM
|RECORD=41|OwnerIndex=730|IndexInSheet=1|OwnerPartId=-1|Location.X=790|Location.Y=370|Color=8388608|FontID=7|IsHidden=T|Text=VISHAY/DALE|Name=MFG NAME
|RECORD=41|OwnerIndex=730|IndexInSheet=2|OwnerPartId=-1|Location.X=790|Location.Y=370|Color=8388608|FontID=7|IsHidden=T|Text=RES|Name=CATEGORY
|RECORD=41|OwnerIndex=730|IndexInSheet=3|OwnerPartId=-1|Location.X=790|Location.Y=370|Color=8388608|FontID=7|IsHidden=T|Text=7/26/2013|Name=ModifyDate
|RECORD=41|OwnerIndex=730|IndexInSheet=4|OwnerPartId=-1|Location.X=788|Location.Y=380|Color=8388608|FontID=7|IsHidden=T|Name=Date
|RECORD=41|OwnerIndex=730|IndexInSheet=5|OwnerPartId=-1|Location.X=778|Location.X_Frac=55769|Location.Y=380|Color=8388608|FontID=7|IsHidden=T|Text=1%|Name=P1
|RECORD=41|OwnerIndex=730|IndexInSheet=6|OwnerPartId=-1|Location.X=778|Location.X_Frac=55769|Location.Y=380|Color=8388608|FontID=7|IsHidden=T|Text=TF|Name=P3
|RECORD=41|OwnerIndex=730|IndexInSheet=7|OwnerPartId=-1|Location.X=778|Location.X_Frac=55769|Location.Y=380|Color=8388608|FontID=7|IsHidden=T|Text=1/8W|Name=P2
|RECORD=41|OwnerIndex=730|IndexInSheet=8|OwnerPartId=-1|Location.X=778|Location.X_Frac=55769|Location.Y=380|Color=8388608|FontID=7|IsHidden=T|Text=125C|Name=MAXTEMP
|RECORD=41|OwnerIndex=730|IndexInSheet=9|OwnerPartId=-1|Location.X=778|Location.X_Frac=55769|Location.Y=380|Color=8388608|FontID=7|IsHidden=T|Text=-55C|Name=MINTEMP
|RECORD=41|OwnerIndex=730|IndexInSheet=10|OwnerPartId=-1|Location.X=778|Location.X_Frac=55769|Location.Y=380|Color=8388608|FontID=7|IsHidden=T|Text=100PPM|Name=OTHER
|RECORD=41|OwnerIndex=730|IndexInSheet=11|OwnerPartId=-1|Location.X=778|Location.X_Frac=55769|Location.Y=380|Color=8388608|FontID=7|IsHidden=T|Text=0805|Name=SIZE
|RECORD=41|OwnerIndex=730|IndexInSheet=12|OwnerPartId=-1|Location.X=778|Location.X_Frac=55769|Location.Y=380|Color=8388608|FontID=7|IsHidden=T|Name=SUB
|RECORD=41|OwnerIndex=730|IndexInSheet=13|OwnerPartId=-1|Location.X=778|Location.X_Frac=55769|Location.Y=380|Color=8388608|FontID=7|IsHidden=T|Text=Digi-Key|Name=Supplier 1|ReadOnlyState=3
|RECORD=41|OwnerIndex=730|IndexInSheet=14|OwnerPartId=-1|Location.X=778|Location.X_Frac=55769|Location.Y=380|Color=8388608|FontID=7|IsHidden=T|Text=541-33.0CCT-ND|Name=Supplier Part Number 1|ReadOnlyState=3
|RECORD=41|OwnerIndex=730|IndexInSheet=15|OwnerPartId=-1|Location.X=773|Location.X_Frac=98077|Location.Y=356|Color=8388608|FontID=1|IsHidden=T|Text=*|Name=SHEETPART
|RECORD=41|OwnerIndex=730|IndexInSheet=16|OwnerPartId=-1|Location.X=773|Location.X_Frac=98077|Location.Y=384|Color=8388608|FontID=1|IsHidden=T|Text=RES, 33 OHM, 1%, 1/8W, TF, 0805|Name=DESC
|RECORD=41|OwnerIndex=730|IndexInSheet=17|OwnerPartId=-1|Location.X=799|Location.Y=354|Color=8388608|FontID=7|Text=33 OHM|Name=VALUE
|RECORD=2|OwnerIndex=730|OwnerPartId=1|FormalType=1|Electrical=4|PinConglomerate=34|PinLength=10|Location.X=800|Location.Y=370|Name=1|Designator=1|PinPropagationDelay=0.000000E+000
|RECORD=2|OwnerIndex=730|OwnerPartId=1|FormalType=1|Electrical=4|PinConglomerate=32|PinLength=10|Location.X=830|Location.Y=370|Name=2|Designator=2|PinPropagationDelay=0.000000E+000
|RECORD=6|OwnerIndex=730|IsNotAccesible=T|IndexInSheet=20|OwnerPartId=1|LineWidth=1|Color=16711680|LocationCount=7|X1=830|Y1=370|X2=827|Y2=373|X3=821|Y3=367|X4=815|Y4=373|X5=809|Y5=367|X6=803|Y6=373|X7=800|Y7=370
|RECORD=41|OwnerIndex=730|IndexInSheet=21|OwnerPartId=-1|Location.X=774|Location.X_Frac=61102|Location.Y=384|Color=8388608|FontID=1|IsHidden=T|Text=<VELENTIUM>|Name=VELENTIUM PART NUM
|RECORD=34|OwnerIndex=730|IndexInSheet=-1|OwnerPartId=-1|Location.X=799|Location.Y=374|Color=8388608|FontID=1|Text=R20|Name=Designator|ReadOnlyState=1
|RECORD=41|OwnerIndex=730|IndexInSheet=-1|OwnerPartId=-1|Location.X=810|Location.Y=360|Color=8388608|FontID=1|IsHidden=T|Text==MFG PART NUM|Name=Comment
|RECORD=44|OwnerIndex=730
|RECORD=45|OwnerIndex=757|IndexInSheet=-1|Description=Chip Resistor, 0805, 2-Leads, Body 2.05x1.25mm, IPC Medium Density|UseComponentLibrary=T|ModelName=RESC2012X50N|ModelType=PCBLIB|DatafileCount=1|ModelDatafileEntity0=RESC2012X50N|ModelDatafileKind0=PCBLib|IsCurrent=T|DatalinksLocked=T|DatabaseDatalinksLocked=T|IntegratedModel=T|DatabaseModel=T
|RECORD=46|OwnerIndex=758
|RECORD=48|OwnerIndex=758
|RECORD=1|LibReference=RES_0805_33|ComponentDescription=RES, 33 OHM, 1%, 1/8W, TF, 0805|PartCount=2|DisplayModeCount=1|IndexInSheet=67|OwnerPartId=-1|Location.X=790|Location.Y=340|CurrentPartId=1|LibraryPath=*|SourceLibraryName=Resistors.IntLib|TargetFileName=*|AreaColor=11599871|Color=128|PartIDLocked=F|DesignItemId=RES_0805_33|AllPinCount=2
|RECORD=41|OwnerIndex=761|OwnerPartId=-1|Location.X=790|Location.Y=340|Color=8388608|FontID=7|IsHidden=T|Text=CRCW080533R0FKEA|Name=MFG PART NUM
|RECORD=41|OwnerIndex=761|IndexInSheet=1|OwnerPartId=-1|Location.X=790|Location.Y=340|Color=8388608|FontID=7|IsHidden=T|Text=VISHAY/DALE|Name=MFG NAME
|RECORD=41|OwnerIndex=761|IndexInSheet=2|OwnerPartId=-1|Location.X=790|Location.Y=340|Color=8388608|FontID=7|IsHidden=T|Text=RES|Name=CATEGORY
|RECORD=41|OwnerIndex=761|IndexInSheet=3|OwnerPartId=-1|Location.X=790|Location.Y=340|Color=8388608|FontID=7|IsHidden=T|Text=7/26/2013|Name=ModifyDate
|RECORD=41|OwnerIndex=761|IndexInSheet=4|OwnerPartId=-1|Location.X=788|Location.Y=350|Color=8388608|FontID=7|IsHidden=T|Name=Date
|RECORD=41|OwnerIndex=761|IndexInSheet=5|OwnerPartId=-1|Location.X=778|Location.X_Frac=55769|Location.Y=350|Color=8388608|FontID=7|IsHidden=T|Text=1%|Name=P1
|RECORD=41|OwnerIndex=761|IndexInSheet=6|OwnerPartId=-1|Location.X=778|Location.X_Frac=55769|Location.Y=350|Color=8388608|FontID=7|IsHidden=T|Text=TF|Name=P3
|RECORD=41|OwnerIndex=761|IndexInSheet=7|OwnerPartId=-1|Location.X=778|Location.X_Frac=55769|Location.Y=350|Color=8388608|FontID=7|IsHidden=T|Text=1/8W|Name=P2
|RECORD=41|OwnerIndex=761|IndexInSheet=8|OwnerPartId=-1|Location.X=778|Location.X_Frac=55769|Location.Y=350|Color=8388608|FontID=7|IsHidden=T|Text=125C|Name=MAXTEMP
|RECORD=41|OwnerIndex=761|IndexInSheet=9|OwnerPartId=-1|Location.X=778|Location.X_Frac=55769|Location.Y=350|Color=8388608|FontID=7|IsHidden=T|Text=-55C|Name=MINTEMP
|RECORD=41|OwnerIndex=761|IndexInSheet=10|OwnerPartId=-1|Location.X=778|Location.X_Frac=55769|Location.Y=350|Color=8388608|FontID=7|IsHidden=T|Text=100PPM|Name=OTHER
|RECORD=41|OwnerIndex=761|IndexInSheet=11|OwnerPartId=-1|Location.X=778|Location.X_Frac=55769|Location.Y=350|Color=8388608|FontID=7|IsHidden=T|Text=0805|Name=SIZE
|RECORD=41|OwnerIndex=761|IndexInSheet=12|OwnerPartId=-1|Location.X=778|Location.X_Frac=55769|Location.Y=350|Color=8388608|FontID=7|IsHidden=T|Name=SUB
|RECORD=41|OwnerIndex=761|IndexInSheet=13|OwnerPartId=-1|Location.X=778|Location.X_Frac=55769|Location.Y=350|Color=8388608|FontID=7|IsHidden=T|Text=Digi-Key|Name=Supplier 1|ReadOnlyState=3
|RECORD=41|OwnerIndex=761|IndexInSheet=14|OwnerPartId=-1|Location.X=778|Location.X_Frac=55769|Location.Y=350|Color=8388608|FontID=7|IsHidden=T|Text=541-33.0CCT-ND|Name=Supplier Part Number 1|ReadOnlyState=3
|RECORD=41|OwnerIndex=761|IndexInSheet=15|OwnerPartId=-1|Location.X=773|Location.X_Frac=98077|Location.Y=326|Color=8388608|FontID=1|IsHidden=T|Text=*|Name=SHEETPART
|RECORD=41|OwnerIndex=761|IndexInSheet=16|OwnerPartId=-1|Location.X=773|Location.X_Frac=98077|Location.Y=354|Color=8388608|FontID=1|IsHidden=T|Text=RES, 33 OHM, 1%, 1/8W, TF, 0805|Name=DESC
|RECORD=41|OwnerIndex=761|IndexInSheet=17|OwnerPartId=-1|Location.X=799|Location.Y=324|Color=8388608|FontID=7|Text=33 OHM|Name=VALUE
|RECORD=2|OwnerIndex=761|OwnerPartId=1|FormalType=1|Electrical=4|PinConglomerate=34|PinLength=10|Location.X=800|Location.Y=340|Name=1|Designator=1|PinPropagationDelay=0.000000E+000
|RECORD=2|OwnerIndex=761|OwnerPartId=1|FormalType=1|Electrical=4|PinConglomerate=32|PinLength=10|Location.X=830|Location.Y=340|Name=2|Designator=2|PinPropagationDelay=0.000000E+000
|RECORD=6|OwnerIndex=761|IsNotAccesible=T|IndexInSheet=20|OwnerPartId=1|LineWidth=1|Color=16711680|LocationCount=7|X1=830|Y1=340|X2=827|Y2=343|X3=821|Y3=337|X4=815|Y4=343|X5=809|Y5=337|X6=803|Y6=343|X7=800|Y7=340
|RECORD=41|OwnerIndex=761|IndexInSheet=21|OwnerPartId=-1|Location.X=774|Location.X_Frac=61102|Location.Y=354|Color=8388608|FontID=1|IsHidden=T|Text=<VELENTIUM>|Name=VELENTIUM PART NUM
|RECORD=34|OwnerIndex=761|IndexInSheet=-1|OwnerPartId=-1|Location.X=799|Location.Y=344|Color=8388608|FontID=1|Text=R21|Name=Designator|ReadOnlyState=1
|RECORD=41|OwnerIndex=761|IndexInSheet=-1|OwnerPartId=-1|Location.X=810|Location.Y=330|Color=8388608|FontID=1|IsHidden=T|Text==MFG PART NUM|Name=Comment
|RECORD=44|OwnerIndex=761
|RECORD=45|OwnerIndex=788|IndexInSheet=-1|Description=Chip Resistor, 0805, 2-Leads, Body 2.05x1.25mm, IPC Medium Density|UseComponentLibrary=T|ModelName=RESC2012X50N|ModelType=PCBLIB|DatafileCount=1|ModelDatafileEntity0=RESC2012X50N|ModelDatafileKind0=PCBLib|IsCurrent=T|DatalinksLocked=T|DatabaseDatalinksLocked=T|IntegratedModel=T|DatabaseModel=T
|RECORD=46|OwnerIndex=789
|RECORD=48|OwnerIndex=789
|RECORD=1|LibReference=SAMTEC-HTSH-105-01-L-DV|ComponentDescription=CONN, HDR, 2X5, VERT, 0.1IN  SHROUDED, SMT, HTSH SERIES|PartCount=2|DisplayModeCount=1|IndexInSheet=68|OwnerPartId=-1|Location.X=870|Location.Y=390|CurrentPartId=1|LibraryPath=*|SourceLibraryName=Connectors.IntLib|TargetFileName=*|AreaColor=11599871|Color=128|PartIDLocked=F|DesignItemId=SAMTEC-HTSH-105-01-L-DV|AllPinCount=10
|RECORD=41|OwnerIndex=792|OwnerPartId=-1|Location.X=870|Location.Y=390|Color=8388608|FontID=7|IsHidden=T|Text=HTST-105-01-L-DV-A|Name=MFG PART NUM
|RECORD=41|OwnerIndex=792|IndexInSheet=1|OwnerPartId=-1|Location.X=870|Location.Y=390|Color=8388608|FontID=7|IsHidden=T|Text=10/10/2013|Name=MODIFY DATE
|RECORD=41|OwnerIndex=792|IndexInSheet=2|OwnerPartId=-1|Location.X=870|Location.Y=390|Color=8388608|FontID=7|IsHidden=T|Text=SAMTEC INC|Name=MFG NAME
|RECORD=41|OwnerIndex=792|IndexInSheet=3|OwnerPartId=-1|Location.X=868|Location.Y=415|Color=8388608|FontID=7|IsHidden=T|Text=CONN, HDR|Name=CATEGORY
|RECORD=41|OwnerIndex=792|IndexInSheet=4|OwnerPartId=-1|Location.X=868|Location.Y=415|Color=8388608|FontID=7|IsHidden=T|Text=125C|Name=MAXTEMP
|RECORD=41|OwnerIndex=792|IndexInSheet=5|OwnerPartId=-1|Location.X=868|Location.Y=415|Color=8388608|FontID=7|IsHidden=T|Text=-55C|Name=MINTEMP
|RECORD=41|OwnerIndex=792|IndexInSheet=6|OwnerPartId=-1|Location.X=868|Location.Y=415|Color=8388608|FontID=7|IsHidden=T|Text=HTSH SERIES|Name=OTHER
|RECORD=41|OwnerIndex=792|IndexInSheet=7|OwnerPartId=-1|Location.X=868|Location.Y=415|Color=8388608|FontID=7|IsHidden=T|Text=VERT|Name=P1
|RECORD=41|OwnerIndex=792|IndexInSheet=8|OwnerPartId=-1|Location.X=868|Location.Y=415|Color=8388608|FontID=7|IsHidden=T|Text=0.1 IN|Name=P2
|RECORD=41|OwnerIndex=792|IndexInSheet=9|OwnerPartId=-1|Location.X=868|Location.Y=415|Color=8388608|FontID=7|IsHidden=T|Text=SHROUDED|Name=P3
|RECORD=41|OwnerIndex=792|IndexInSheet=10|OwnerPartId=-1|Location.X=868|Location.Y=415|Color=8388608|FontID=7|IsHidden=T|Text=SMT|Name=SIZE
|RECORD=41|OwnerIndex=792|IndexInSheet=11|OwnerPartId=-1|Location.X=868|Location.Y=415|Color=8388608|FontID=7|IsHidden=T|Name=SUB
|RECORD=41|OwnerIndex=792|IndexInSheet=12|OwnerPartId=-1|Location.X=868|Location.Y=309|Color=8388608|FontID=7|IsHidden=T|Name=SHEETPART
|RECORD=41|OwnerIndex=792|IndexInSheet=13|OwnerPartId=-1|Location.X=868|Location.Y=309|Color=8388608|FontID=7|IsHidden=T|Name=DATE
|RECORD=41|OwnerIndex=792|IndexInSheet=14|OwnerPartId=-1|Location.X=868|Location.Y=419|Color=8388608|FontID=1|IsHidden=T|Text=CONN, HDR, 2X5, VERT, 0.1IN  SHROUDED, SMT, HTSH SERIES|Name=DESC
|RECORD=41|OwnerIndex=792|IndexInSheet=15|OwnerPartId=-1|Location.X=868|Location.Y=419|Color=8388608|FontID=1|IsHidden=T|Text=<VALENTIUM>|Name=VALENTIUM PART NUM
|RECORD=41|OwnerIndex=792|IndexInSheet=16|OwnerPartId=-1|Location.X=860|Location.Y=422|Color=8388608|FontID=1|IsHidden=T|Text=Digi-Key|Name=Supplier 1|ReadOnlyState=3
|RECORD=41|OwnerIndex=792|IndexInSheet=17|OwnerPartId=-1|Location.X=860|Location.Y=422|Color=8388608|FontID=1|IsHidden=T|Text=SAM8809-ND|Name=Supplier Part Number 1|ReadOnlyState=3
|RECORD=41|OwnerIndex=792|IndexInSheet=18|OwnerPartId=-1|Location.X=908|Location.X_Frac=50000|Location.Y=328|Color=8388608|FontID=7|Text=2X5|Name=VALUE
|RECORD=2|OwnerIndex=792|OwnerPartId=1|FormalType=1|Electrical=4|PinConglomerate=50|PinLength=30|Location.X=910|Location.Y=350|Name=P9|Designator=9|PinPropagationDelay=0.000000E+000
|RECORD=2|OwnerIndex=792|OwnerPartId=1|FormalType=1|Electrical=4|PinConglomerate=50|PinLength=30|Location.X=910|Location.Y=380|Name=P3|Designator=3|PinPropagationDelay=0.000000E+000
|RECORD=2|OwnerIndex=792|OwnerPartId=1|FormalType=1|Electrical=4|PinConglomerate=48|PinLength=30|Location.X=950|Location.Y=350|Name=P10|Designator=10|PinPropagationDelay=0.000000E+000
|RECORD=2|OwnerIndex=792|OwnerPartId=1|FormalType=1|Electrical=4|PinConglomerate=48|PinLength=30|Location.X=950|Location.Y=380|Name=P4|Designator=4|PinPropagationDelay=0.000000E+000
|RECORD=2|OwnerIndex=792|OwnerPartId=1|FormalType=1|Electrical=4|PinConglomerate=50|PinLength=30|Location.X=910|Location.Y=390|Name=P1|Designator=1|PinPropagationDelay=0.000000E+000
|RECORD=2|OwnerIndex=792|OwnerPartId=1|FormalType=1|Electrical=4|PinConglomerate=50|PinLength=30|Location.X=910|Location.Y=370|Name=P5|Designator=5|PinPropagationDelay=0.000000E+000
|RECORD=2|OwnerIndex=792|OwnerPartId=1|FormalType=1|Electrical=4|PinConglomerate=50|PinLength=30|Location.X=910|Location.Y=360|Name=P7|Designator=7|PinPropagationDelay=0.000000E+000
|RECORD=2|OwnerIndex=792|OwnerPartId=1|FormalType=1|Electrical=4|PinConglomerate=48|PinLength=30|Location.X=950|Location.Y=390|Name=P2|Designator=2|PinPropagationDelay=0.000000E+000
|RECORD=2|OwnerIndex=792|OwnerPartId=1|FormalType=1|Electrical=4|PinConglomerate=48|PinLength=30|Location.X=950|Location.Y=370|Name=P6|Designator=6|PinPropagationDelay=0.000000E+000
|RECORD=2|OwnerIndex=792|OwnerPartId=1|FormalType=1|Electrical=4|PinConglomerate=48|PinLength=30|Location.X=950|Location.Y=360|Name=P8|Designator=8|PinPropagationDelay=0.000000E+000
|RECORD=13|OwnerIndex=792|IsNotAccesible=T|IndexInSheet=29|OwnerPartId=1|Location.X=917|Location.X_Frac=50000|Location.Y=365|Corner.X=922|Corner.X_Frac=50000|Corner.Y=360|LineWidth=1|Color=16711680
|RECORD=13|OwnerIndex=792|IsNotAccesible=T|IndexInSheet=30|OwnerPartId=1|Location.X=917|Location.X_Frac=50000|Location.Y=355|Corner.X=922|Corner.X_Frac=50000|Corner.Y=360|LineWidth=1|Color=16711680
|RECORD=13|OwnerIndex=792|IsNotAccesible=T|IndexInSheet=31|OwnerPartId=1|Location.X=917|Location.X_Frac=50000|Location.Y=355|Corner.X=922|Corner.X_Frac=50000|Corner.Y=350|LineWidth=1|Color=16711680
|RECORD=13|OwnerIndex=792|IsNotAccesible=T|IndexInSheet=32|OwnerPartId=1|Location.X=917|Location.X_Frac=50000|Location.Y=345|Corner.X=922|Corner.X_Frac=50000|Corner.Y=350|LineWidth=1|Color=16711680
|RECORD=13|OwnerIndex=792|IsNotAccesible=T|IndexInSheet=33|OwnerPartId=1|Location.X=917|Location.X_Frac=50000|Location.Y=395|Corner.X=922|Corner.X_Frac=50000|Corner.Y=390|LineWidth=1|Color=16711680
|RECORD=13|OwnerIndex=792|IsNotAccesible=T|IndexInSheet=34|OwnerPartId=1|Location.X=917|Location.X_Frac=50000|Location.Y=385|Corner.X=922|Corner.X_Frac=50000|Corner.Y=390|LineWidth=1|Color=16711680
|RECORD=13|OwnerIndex=792|IsNotAccesible=T|IndexInSheet=35|OwnerPartId=1|Location.X=917|Location.X_Frac=50000|Location.Y=385|Corner.X=922|Corner.X_Frac=50000|Corner.Y=380|LineWidth=1|Color=16711680
|RECORD=13|OwnerIndex=792|IsNotAccesible=T|IndexInSheet=36|OwnerPartId=1|Location.X=917|Location.X_Frac=50000|Location.Y=375|Corner.X=922|Corner.X_Frac=50000|Corner.Y=380|LineWidth=1|Color=16711680
|RECORD=13|OwnerIndex=792|IsNotAccesible=T|IndexInSheet=37|OwnerPartId=1|Location.X=942|Location.X_Frac=50000|Location.Y=355|Corner.X=937|Corner.X_Frac=50000|Corner.Y=350|LineWidth=1|Color=16711680
|RECORD=13|OwnerIndex=792|IsNotAccesible=T|IndexInSheet=38|OwnerPartId=1|Location.X=942|Location.X_Frac=50000|Location.Y=355|Corner.X=937|Corner.X_Frac=50000|Corner.Y=360|LineWidth=1|Color=16711680
|RECORD=13|OwnerIndex=792|IsNotAccesible=T|IndexInSheet=39|OwnerPartId=1|Location.X=942|Location.X_Frac=50000|Location.Y=365|Corner.X=937|Corner.X_Frac=50000|Corner.Y=360|LineWidth=1|Color=16711680
|RECORD=13|OwnerIndex=792|IsNotAccesible=T|IndexInSheet=40|OwnerPartId=1|Location.X=942|Location.X_Frac=50000|Location.Y=345|Corner.X=937|Corner.X_Frac=50000|Corner.Y=350|LineWidth=1|Color=16711680
|RECORD=13|OwnerIndex=792|IsNotAccesible=T|IndexInSheet=41|OwnerPartId=1|Location.X=942|Location.X_Frac=50000|Location.Y=375|Corner.X=937|Corner.X_Frac=50000|Corner.Y=380|LineWidth=1|Color=16711680
|RECORD=13|OwnerIndex=792|IsNotAccesible=T|IndexInSheet=42|OwnerPartId=1|Location.X=942|Location.X_Frac=50000|Location.Y=385|Corner.X=937|Corner.X_Frac=50000|Corner.Y=380|LineWidth=1|Color=16711680
|RECORD=13|OwnerIndex=792|IsNotAccesible=T|IndexInSheet=43|OwnerPartId=1|Location.X=942|Location.X_Frac=50000|Location.Y=385|Corner.X=937|Corner.X_Frac=50000|Corner.Y=390|LineWidth=1|Color=16711680
|RECORD=13|OwnerIndex=792|IsNotAccesible=T|IndexInSheet=44|OwnerPartId=1|Location.X=942|Location.X_Frac=50000|Location.Y=395|Corner.X=937|Corner.X_Frac=50000|Corner.Y=390|LineWidth=1|Color=16711680
|RECORD=13|OwnerIndex=792|IsNotAccesible=T|IndexInSheet=45|OwnerPartId=1|Location.X=917|Location.X_Frac=50000|Location.Y=375|Corner.X=922|Corner.X_Frac=50000|Corner.Y=370|LineWidth=1|Color=16711680
|RECORD=13|OwnerIndex=792|IsNotAccesible=T|IndexInSheet=46|OwnerPartId=1|Location.X=917|Location.X_Frac=50000|Location.Y=365|Corner.X=922|Corner.X_Frac=50000|Corner.Y=370|LineWidth=1|Color=16711680
|RECORD=13|OwnerIndex=792|IsNotAccesible=T|IndexInSheet=47|OwnerPartId=1|Location.X=942|Location.X_Frac=50000|Location.Y=365|Corner.X=937|Corner.X_Frac=50000|Corner.Y=370|LineWidth=1|Color=16711680
|RECORD=13|OwnerIndex=792|IsNotAccesible=T|IndexInSheet=48|OwnerPartId=1|Location.X=942|Location.X_Frac=50000|Location.Y=375|Corner.X=937|Corner.X_Frac=50000|Corner.Y=370|LineWidth=1|Color=16711680
|RECORD=13|OwnerIndex=792|IsNotAccesible=T|IndexInSheet=49|OwnerPartId=1|Location.X=950|Location.Y=350|Corner.X=937|Corner.X_Frac=50000|Corner.Y=350|LineWidth=1|Color=16711680
|RECORD=13|OwnerIndex=792|IsNotAccesible=T|IndexInSheet=50|OwnerPartId=1|Location.X=950|Location.Y=360|Corner.X=937|Corner.X_Frac=50000|Corner.Y=360|LineWidth=1|Color=16711680
|RECORD=13|OwnerIndex=792|IsNotAccesible=T|IndexInSheet=51|OwnerPartId=1|Location.X=950|Location.Y=370|Corner.X=937|Corner.X_Frac=50000|Corner.Y=370|LineWidth=1|Color=16711680
|RECORD=13|OwnerIndex=792|IsNotAccesible=T|IndexInSheet=52|OwnerPartId=1|Location.X=950|Location.Y=380|Corner.X=937|Corner.X_Frac=50000|Corner.Y=380|LineWidth=1|Color=16711680
|RECORD=13|OwnerIndex=792|IsNotAccesible=T|IndexInSheet=53|OwnerPartId=1|Location.X=950|Location.Y=390|Corner.X=937|Corner.X_Frac=50000|Corner.Y=390|LineWidth=1|Color=16711680
|RECORD=13|OwnerIndex=792|IsNotAccesible=T|IndexInSheet=54|OwnerPartId=1|Location.X=922|Location.Y=390|Corner.X=909|Corner.X_Frac=50000|Corner.Y=390|LineWidth=1|Color=16711680
|RECORD=13|OwnerIndex=792|IsNotAccesible=T|IndexInSheet=55|OwnerPartId=1|Location.X=922|Location.Y=380|Corner.X=909|Corner.X_Frac=50000|Corner.Y=380|LineWidth=1|Color=16711680
|RECORD=13|OwnerIndex=792|IsNotAccesible=T|IndexInSheet=56|OwnerPartId=1|Location.X=922|Location.Y=370|Corner.X=909|Corner.X_Frac=50000|Corner.Y=370|LineWidth=1|Color=16711680
|RECORD=13|OwnerIndex=792|IsNotAccesible=T|IndexInSheet=57|OwnerPartId=1|Location.X=922|Location.Y=360|Corner.X=909|Corner.X_Frac=50000|Corner.Y=360|LineWidth=1|Color=16711680
|RECORD=13|OwnerIndex=792|IsNotAccesible=T|IndexInSheet=58|OwnerPartId=1|Location.X=922|Location.Y=350|Corner.X=909|Corner.X_Frac=50000|Corner.Y=350|LineWidth=1|Color=16711680
|RECORD=14|OwnerIndex=792|IsNotAccesible=T|IndexInSheet=59|OwnerPartId=1|Location.X=910|Location.Y=340|Corner.X=950|Corner.Y=400|Color=128|AreaColor=11599871|IsSolid=T|Transparent=T
|RECORD=34|OwnerIndex=792|IndexInSheet=-1|OwnerPartId=-1|Location.X=908|Location.X_Frac=50000|Location.Y=400|Color=8388608|FontID=1|Text=U5|Name=Designator|ReadOnlyState=1
|RECORD=41|OwnerIndex=792|IndexInSheet=-1|OwnerPartId=-1|Location.X=910|Location.Y=310|Color=8388608|FontID=1|IsHidden=T|Text==MFG PART NUM|Name=Comment
|RECORD=44|OwnerIndex=792
|RECORD=45|OwnerIndex=865|IndexInSheet=-1|UseComponentLibrary=T|ModelName=SAMTEC_HTST-105-01-L-DV-A|ModelType=PCBLIB|DatafileCount=1|ModelDatafileEntity0=SAMTEC_HTST-105-01-L-DV-A|ModelDatafileKind0=PCBLib|IsCurrent=T|DatalinksLocked=T|DatabaseDatalinksLocked=T|IntegratedModel=T|DatabaseModel=T
|RECORD=46|OwnerIndex=866
|RECORD=48|OwnerIndex=866
|RECORD=1|LibReference=BAT54SW|ComponentDescription=DIO, SCHOTTKY, BAT54S, DUAL SERIES, 30V, 200MA, SC-70|PartCount=2|DisplayModeCount=1|IndexInSheet=69|OwnerPartId=-1|Location.X=1020|Location.Y=180|Orientation=1|CurrentPartId=1|LibraryPath=*|SourceLibraryName=Passives.IntLib|TargetFileName=*|AreaColor=11599871|Color=128|PartIDLocked=F|DesignItemId=BAT54SW|AllPinCount=3
|RECORD=41|OwnerIndex=869|OwnerPartId=-1|Location.X=1009|Location.Y=252|Color=8388608|FontID=7|IsHidden=T|Text=BAT54SWQ-7-F|Name=MFG PART NUM
|RECORD=41|OwnerIndex=869|IndexInSheet=1|OwnerPartId=-1|Location.X=1009|Location.Y=252|Color=8388608|FontID=7|IsHidden=T|Text=9/4/2013|Name=MODIFY DATE
|RECORD=41|OwnerIndex=869|IndexInSheet=2|OwnerPartId=-1|Location.X=1009|Location.Y=252|Color=8388608|FontID=7|IsHidden=T|Text=DIODES INC|Name=MFG NAME
|RECORD=41|OwnerIndex=869|IndexInSheet=3|OwnerPartId=-1|Location.X=1009|Location.Y=252|Color=8388608|FontID=7|IsHidden=T|Text=DIO, SCHOTTKY|Name=CATEGORY
|RECORD=41|OwnerIndex=869|IndexInSheet=4|OwnerPartId=-1|Location.X=1009|Location.Y=252|Color=8388608|FontID=7|IsHidden=T|Name=DATE
|RECORD=41|OwnerIndex=869|IndexInSheet=5|OwnerPartId=-1|Location.X=1009|Location.Y=252|Color=8388608|FontID=7|IsHidden=T|Text=150C|Name=MAXTEMP
|RECORD=41|OwnerIndex=869|IndexInSheet=6|OwnerPartId=-1|Location.X=1009|Location.Y=252|Color=8388608|FontID=7|IsHidden=T|Text=-55C|Name=MINTEMP
|RECORD=41|OwnerIndex=869|IndexInSheet=7|OwnerPartId=-1|Location.X=1009|Location.Y=252|Color=8388608|FontID=7|IsHidden=T|Text=SERIES|Name=OTHER
|RECORD=41|OwnerIndex=869|IndexInSheet=8|OwnerPartId=-1|Location.X=1009|Location.Y=252|Color=8388608|FontID=7|IsHidden=T|Text=SCHOTTKY|Name=P1
|RECORD=41|OwnerIndex=869|IndexInSheet=9|OwnerPartId=-1|Location.X=1009|Location.Y=252|Color=8388608|FontID=7|IsHidden=T|Text=30V|Name=P2
|RECORD=41|OwnerIndex=869|IndexInSheet=10|OwnerPartId=-1|Location.X=1009|Location.Y=252|Color=8388608|FontID=7|IsHidden=T|Text=200mA,200mW|Name=P3
|RECORD=41|OwnerIndex=869|IndexInSheet=11|OwnerPartId=-1|Location.X=1009|Location.Y=252|Color=8388608|FontID=7|IsHidden=T|Text=SC-70|Name=SIZE
|RECORD=41|OwnerIndex=869|IndexInSheet=12|OwnerPartId=-1|Location.X=1009|Location.Y=252|Color=8388608|FontID=7|IsHidden=T|Name=SUB
|RECORD=41|OwnerIndex=869|IndexInSheet=13|OwnerPartId=-1|Location.X=1009|Location.Y=252|Color=8388608|FontID=1|IsHidden=T|Text=*|Name=SHEETPART
|RECORD=41|OwnerIndex=869|IndexInSheet=14|OwnerPartId=-1|Location.X=1009|Location.Y=252|Color=8388608|FontID=1|IsHidden=T|Text=DIO, SCHOTTKY, BAT54S, DUAL SERIES, 30V, 200MA, SC-70|Name=DESC
|RECORD=41|OwnerIndex=869|IndexInSheet=15|OwnerPartId=-1|Location.X=1009|Location.Y=252|Color=8388608|FontID=1|IsHidden=T|Text=Digi-Key|Name=Supplier 1|ReadOnlyState=3
|RECORD=41|OwnerIndex=869|IndexInSheet=16|OwnerPartId=-1|Location.X=1009|Location.Y=252|Color=8388608|FontID=1|IsHidden=T|Text=BAT54SWQ-7-FDICT-ND|Name=Supplier Part Number 1|ReadOnlyState=3
|RECORD=41|OwnerIndex=869|IndexInSheet=17|OwnerPartId=-1|Location.X=1051|Location.Y=205|Color=8388608|FontID=7|Text=BAT54SW|Name=VALUE
|RECORD=2|OwnerIndex=869|OwnerPartId=1|FormalType=1|Electrical=4|PinConglomerate=51|PinLength=20|Location.X=1040|Location.Y=200|Name=2|Designator=2|SwapIdPin=1|SwapIDPart=1|PinPropagationDelay=0.000000E+000
|RECORD=2|OwnerIndex=869|OwnerPartId=1|FormalType=1|Electrical=4|PinConglomerate=49|PinLength=20|Location.X=1030|Location.Y=230|Name=3|Designator=3|SwapIdPin=2|SwapIDPart=1|PinPropagationDelay=0.000000E+000
|RECORD=2|OwnerIndex=869|OwnerPartId=1|FormalType=1|Electrical=4|PinConglomerate=51|PinLength=20|Location.X=1020|Location.Y=200|Name=1|Designator=1|SwapIdPin=3|SwapIDPart=1|PinPropagationDelay=0.000000E+000
|RECORD=13|OwnerIndex=869|IsNotAccesible=T|IndexInSheet=21|OwnerPartId=1|Location.X=1020|Location.Y=230|Corner.X=1020|Corner.Y=220|LineWidth=1|Color=16711680
|RECORD=13|OwnerIndex=869|IsNotAccesible=T|IndexInSheet=22|OwnerPartId=1|Location.X=1030|Location.Y=208|Corner.X=1050|Corner.Y=208|LineWidth=1|Color=16711680
|RECORD=13|OwnerIndex=869|IsNotAccesible=T|IndexInSheet=23|OwnerPartId=1|Location.X=1040|Location.Y=210|Corner.X=1040|Corner.Y=200|LineWidth=1|Color=16711680
|RECORD=13|OwnerIndex=869|IsNotAccesible=T|IndexInSheet=24|OwnerPartId=1|Location.X=1040|Location.Y=230|Corner.X=1040|Corner.Y=220|LineWidth=1|Color=16711680
|RECORD=13|OwnerIndex=869|IsNotAccesible=T|IndexInSheet=25|OwnerPartId=1|Location.X=1020|Location.Y=210|Corner.X=1020|Corner.Y=200|LineWidth=1|Color=16711680
|RECORD=13|OwnerIndex=869|IsNotAccesible=T|IndexInSheet=26|OwnerPartId=1|Location.X=1010|Location.Y=220|Corner.X=1030|Corner.Y=220|LineWidth=1|Color=16711680
|RECORD=7|OwnerIndex=869|IsNotAccesible=T|IndexInSheet=27|OwnerPartId=1|LineWidth=1|Color=16711680|AreaColor=16711680|IsSolid=T|LocationCount=3|X1=1020|Y1=220|Y1_Frac=20000|X2=1012|X2_Frac=50000|Y2=207|Y2_Frac=70000|X3=1027|X3_Frac=50000|Y3=207|Y3_Frac=70000
|RECORD=7|OwnerIndex=869|IsNotAccesible=T|IndexInSheet=28|OwnerPartId=1|LineWidth=1|Color=16711680|AreaColor=16711680|IsSolid=T|LocationCount=3|X1=1040|Y1=208|X2=1047|X2_Frac=50000|Y2=220|Y2_Frac=50000|X3=1032|X3_Frac=50000|Y3=220|Y3_Frac=50000
|RECORD=6|OwnerIndex=869|IsNotAccesible=T|IndexInSheet=29|OwnerPartId=1|LineWidth=1|Color=16711680|LocationCount=2|X1=1020|Y1=230|X2=1040|Y2=230
|RECORD=41|OwnerIndex=869|IndexInSheet=30|OwnerPartId=-1|Location.X=1009|Location.Y=252|Color=8388608|FontID=1|IsHidden=T|Text=<VALENTIUM>|Name=VALENTIUM PART NUM
|RECORD=34|OwnerIndex=869|IndexInSheet=-1|OwnerPartId=-1|Location.X=1051|Location.Y=217|Color=8388608|FontID=1|Text=D8|Name=Designator|ReadOnlyState=1
|RECORD=41|OwnerIndex=869|IndexInSheet=-1|OwnerPartId=-1|Location.X=1009|Location.Y=252|Color=8388608|FontID=1|IsHidden=T|Text=BAT54SW|Name=Comment
|RECORD=44|OwnerIndex=869
|RECORD=45|OwnerIndex=906|IndexInSheet=-1|Description=SOT323-3 (SC70), 3-Leads, Body 2.00x2.10mm, Pitch 0.65mm, IPC Medium Density|UseComponentLibrary=T|ModelName=SOT65P210X110-3N|ModelType=PCBLIB|DatafileCount=1|ModelDatafileEntity0=SOT65P210X110-3N|ModelDatafileKind0=PCBLib|IsCurrent=T|DatalinksLocked=T|DatabaseDatalinksLocked=T|IntegratedModel=T|DatabaseModel=T
|RECORD=46|OwnerIndex=907
|RECORD=48|OwnerIndex=907
|RECORD=1|LibReference=BAT54SW|ComponentDescription=DIO, SCHOTTKY, BAT54S, DUAL SERIES, 30V, 200MA, SC-70|PartCount=2|DisplayModeCount=1|IndexInSheet=70|OwnerPartId=-1|Location.X=880|Location.Y=180|Orientation=1|CurrentPartId=1|LibraryPath=*|SourceLibraryName=Passives.IntLib|TargetFileName=*|AreaColor=11599871|Color=128|PartIDLocked=F|DesignItemId=BAT54SW|AllPinCount=3
|RECORD=41|OwnerIndex=910|OwnerPartId=-1|Location.X=869|Location.Y=252|Color=8388608|FontID=7|IsHidden=T|Text=BAT54SWQ-7-F|Name=MFG PART NUM
|RECORD=41|OwnerIndex=910|IndexInSheet=1|OwnerPartId=-1|Location.X=869|Location.Y=252|Color=8388608|FontID=7|IsHidden=T|Text=9/4/2013|Name=MODIFY DATE
|RECORD=41|OwnerIndex=910|IndexInSheet=2|OwnerPartId=-1|Location.X=869|Location.Y=252|Color=8388608|FontID=7|IsHidden=T|Text=DIODES INC|Name=MFG NAME
|RECORD=41|OwnerIndex=910|IndexInSheet=3|OwnerPartId=-1|Location.X=869|Location.Y=252|Color=8388608|FontID=7|IsHidden=T|Text=DIO, SCHOTTKY|Name=CATEGORY
|RECORD=41|OwnerIndex=910|IndexInSheet=4|OwnerPartId=-1|Location.X=869|Location.Y=252|Color=8388608|FontID=7|IsHidden=T|Name=DATE
|RECORD=41|OwnerIndex=910|IndexInSheet=5|OwnerPartId=-1|Location.X=869|Location.Y=252|Color=8388608|FontID=7|IsHidden=T|Text=150C|Name=MAXTEMP
|RECORD=41|OwnerIndex=910|IndexInSheet=6|OwnerPartId=-1|Location.X=869|Location.Y=252|Color=8388608|FontID=7|IsHidden=T|Text=-55C|Name=MINTEMP
|RECORD=41|OwnerIndex=910|IndexInSheet=7|OwnerPartId=-1|Location.X=869|Location.Y=252|Color=8388608|FontID=7|IsHidden=T|Text=SERIES|Name=OTHER
|RECORD=41|OwnerIndex=910|IndexInSheet=8|OwnerPartId=-1|Location.X=869|Location.Y=252|Color=8388608|FontID=7|IsHidden=T|Text=SCHOTTKY|Name=P1
|RECORD=41|OwnerIndex=910|IndexInSheet=9|OwnerPartId=-1|Location.X=869|Location.Y=252|Color=8388608|FontID=7|IsHidden=T|Text=30V|Name=P2
|RECORD=41|OwnerIndex=910|IndexInSheet=10|OwnerPartId=-1|Location.X=869|Location.Y=252|Color=8388608|FontID=7|IsHidden=T|Text=200mA,200mW|Name=P3
|RECORD=41|OwnerIndex=910|IndexInSheet=11|OwnerPartId=-1|Location.X=869|Location.Y=252|Color=8388608|FontID=7|IsHidden=T|Text=SC-70|Name=SIZE
|RECORD=41|OwnerIndex=910|IndexInSheet=12|OwnerPartId=-1|Location.X=869|Location.Y=252|Color=8388608|FontID=7|IsHidden=T|Name=SUB
|RECORD=41|OwnerIndex=910|IndexInSheet=13|OwnerPartId=-1|Location.X=869|Location.Y=252|Color=8388608|FontID=1|IsHidden=T|Text=*|Name=SHEETPART
|RECORD=41|OwnerIndex=910|IndexInSheet=14|OwnerPartId=-1|Location.X=869|Location.Y=252|Color=8388608|FontID=1|IsHidden=T|Text=DIO, SCHOTTKY, BAT54S, DUAL SERIES, 30V, 200MA, SC-70|Name=DESC
|RECORD=41|OwnerIndex=910|IndexInSheet=15|OwnerPartId=-1|Location.X=869|Location.Y=252|Color=8388608|FontID=1|IsHidden=T|Text=Digi-Key|Name=Supplier 1|ReadOnlyState=3
|RECORD=41|OwnerIndex=910|IndexInSheet=16|OwnerPartId=-1|Location.X=869|Location.Y=252|Color=8388608|FontID=1|IsHidden=T|Text=BAT54SWQ-7-FDICT-ND|Name=Supplier Part Number 1|ReadOnlyState=3
|RECORD=41|OwnerIndex=910|IndexInSheet=17|OwnerPartId=-1|Location.X=911|Location.Y=205|Color=8388608|FontID=7|Text=BAT54SW|Name=VALUE
|RECORD=2|OwnerIndex=910|OwnerPartId=1|FormalType=1|Electrical=4|PinConglomerate=51|PinLength=20|Location.X=900|Location.Y=200|Name=2|Designator=2|SwapIdPin=1|SwapIDPart=1|PinPropagationDelay=0.000000E+000
|RECORD=2|OwnerIndex=910|OwnerPartId=1|FormalType=1|Electrical=4|PinConglomerate=49|PinLength=20|Location.X=890|Location.Y=230|Name=3|Designator=3|SwapIdPin=2|SwapIDPart=1|PinPropagationDelay=0.000000E+000
|RECORD=2|OwnerIndex=910|OwnerPartId=1|FormalType=1|Electrical=4|PinConglomerate=51|PinLength=20|Location.X=880|Location.Y=200|Name=1|Designator=1|SwapIdPin=3|SwapIDPart=1|PinPropagationDelay=0.000000E+000
|RECORD=13|OwnerIndex=910|IsNotAccesible=T|IndexInSheet=21|OwnerPartId=1|Location.X=880|Location.Y=230|Corner.X=880|Corner.Y=220|LineWidth=1|Color=16711680
|RECORD=13|OwnerIndex=910|IsNotAccesible=T|IndexInSheet=22|OwnerPartId=1|Location.X=890|Location.Y=208|Corner.X=910|Corner.Y=208|LineWidth=1|Color=16711680
|RECORD=13|OwnerIndex=910|IsNotAccesible=T|IndexInSheet=23|OwnerPartId=1|Location.X=900|Location.Y=210|Corner.X=900|Corner.Y=200|LineWidth=1|Color=16711680
|RECORD=13|OwnerIndex=910|IsNotAccesible=T|IndexInSheet=24|OwnerPartId=1|Location.X=900|Location.Y=230|Corner.X=900|Corner.Y=220|LineWidth=1|Color=16711680
|RECORD=13|OwnerIndex=910|IsNotAccesible=T|IndexInSheet=25|OwnerPartId=1|Location.X=880|Location.Y=210|Corner.X=880|Corner.Y=200|LineWidth=1|Color=16711680
|RECORD=13|OwnerIndex=910|IsNotAccesible=T|IndexInSheet=26|OwnerPartId=1|Location.X=870|Location.Y=220|Corner.X=890|Corner.Y=220|LineWidth=1|Color=16711680
|RECORD=7|OwnerIndex=910|IsNotAccesible=T|IndexInSheet=27|OwnerPartId=1|LineWidth=1|Color=16711680|AreaColor=16711680|IsSolid=T|LocationCount=3|X1=880|Y1=220|Y1_Frac=20000|X2=872|X2_Frac=50000|Y2=207|Y2_Frac=70000|X3=887|X3_Frac=50000|Y3=207|Y3_Frac=70000
|RECORD=7|OwnerIndex=910|IsNotAccesible=T|IndexInSheet=28|OwnerPartId=1|LineWidth=1|Color=16711680|AreaColor=16711680|IsSolid=T|LocationCount=3|X1=900|Y1=208|X2=907|X2_Frac=50000|Y2=220|Y2_Frac=50000|X3=892|X3_Frac=50000|Y3=220|Y3_Frac=50000
|RECORD=6|OwnerIndex=910|IsNotAccesible=T|IndexInSheet=29|OwnerPartId=1|LineWidth=1|Color=16711680|LocationCount=2|X1=880|Y1=230|X2=900|Y2=230
|RECORD=41|OwnerIndex=910|IndexInSheet=30|OwnerPartId=-1|Location.X=869|Location.Y=252|Color=8388608|FontID=1|IsHidden=T|Text=<VALENTIUM>|Name=VALENTIUM PART NUM
|RECORD=34|OwnerIndex=910|IndexInSheet=-1|OwnerPartId=-1|Location.X=911|Location.Y=217|Color=8388608|FontID=1|Text=D7|Name=Designator|ReadOnlyState=1
|RECORD=41|OwnerIndex=910|IndexInSheet=-1|OwnerPartId=-1|Location.X=869|Location.Y=252|Color=8388608|FontID=1|IsHidden=T|Text=BAT54SW|Name=Comment
|RECORD=44|OwnerIndex=910
|RECORD=45|OwnerIndex=947|IndexInSheet=-1|Description=SOT323-3 (SC70), 3-Leads, Body 2.00x2.10mm, Pitch 0.65mm, IPC Medium Density|UseComponentLibrary=T|ModelName=SOT65P210X110-3N|ModelType=PCBLIB|DatafileCount=1|ModelDatafileEntity0=SOT65P210X110-3N|ModelDatafileKind0=PCBLib|IsCurrent=T|DatalinksLocked=T|DatabaseDatalinksLocked=T|IntegratedModel=T|DatabaseModel=T
|RECORD=46|OwnerIndex=948
|RECORD=48|OwnerIndex=948
|RECORD=1|LibReference=BAT54SW|ComponentDescription=DIO, SCHOTTKY, BAT54S, DUAL SERIES, 30V, 200MA, SC-70|PartCount=2|DisplayModeCount=1|IndexInSheet=71|OwnerPartId=-1|Location.X=740|Location.Y=180|Orientation=1|CurrentPartId=1|LibraryPath=*|SourceLibraryName=Passives.IntLib|TargetFileName=*|AreaColor=11599871|Color=128|PartIDLocked=F|DesignItemId=BAT54SW|AllPinCount=3
|RECORD=41|OwnerIndex=951|OwnerPartId=-1|Location.X=729|Location.Y=252|Color=8388608|FontID=7|IsHidden=T|Text=BAT54SWQ-7-F|Name=MFG PART NUM
|RECORD=41|OwnerIndex=951|IndexInSheet=1|OwnerPartId=-1|Location.X=729|Location.Y=252|Color=8388608|FontID=7|IsHidden=T|Text=9/4/2013|Name=MODIFY DATE
|RECORD=41|OwnerIndex=951|IndexInSheet=2|OwnerPartId=-1|Location.X=729|Location.Y=252|Color=8388608|FontID=7|IsHidden=T|Text=DIODES INC|Name=MFG NAME
|RECORD=41|OwnerIndex=951|IndexInSheet=3|OwnerPartId=-1|Location.X=729|Location.Y=252|Color=8388608|FontID=7|IsHidden=T|Text=DIO, SCHOTTKY|Name=CATEGORY
|RECORD=41|OwnerIndex=951|IndexInSheet=4|OwnerPartId=-1|Location.X=729|Location.Y=252|Color=8388608|FontID=7|IsHidden=T|Name=DATE
|RECORD=41|OwnerIndex=951|IndexInSheet=5|OwnerPartId=-1|Location.X=729|Location.Y=252|Color=8388608|FontID=7|IsHidden=T|Text=150C|Name=MAXTEMP
|RECORD=41|OwnerIndex=951|IndexInSheet=6|OwnerPartId=-1|Location.X=729|Location.Y=252|Color=8388608|FontID=7|IsHidden=T|Text=-55C|Name=MINTEMP
|RECORD=41|OwnerIndex=951|IndexInSheet=7|OwnerPartId=-1|Location.X=729|Location.Y=252|Color=8388608|FontID=7|IsHidden=T|Text=SERIES|Name=OTHER
|RECORD=41|OwnerIndex=951|IndexInSheet=8|OwnerPartId=-1|Location.X=729|Location.Y=252|Color=8388608|FontID=7|IsHidden=T|Text=SCHOTTKY|Name=P1
|RECORD=41|OwnerIndex=951|IndexInSheet=9|OwnerPartId=-1|Location.X=729|Location.Y=252|Color=8388608|FontID=7|IsHidden=T|Text=30V|Name=P2
|RECORD=41|OwnerIndex=951|IndexInSheet=10|OwnerPartId=-1|Location.X=729|Location.Y=252|Color=8388608|FontID=7|IsHidden=T|Text=200mA,200mW|Name=P3
|RECORD=41|OwnerIndex=951|IndexInSheet=11|OwnerPartId=-1|Location.X=729|Location.Y=252|Color=8388608|FontID=7|IsHidden=T|Text=SC-70|Name=SIZE
|RECORD=41|OwnerIndex=951|IndexInSheet=12|OwnerPartId=-1|Location.X=729|Location.Y=252|Color=8388608|FontID=7|IsHidden=T|Name=SUB
|RECORD=41|OwnerIndex=951|IndexInSheet=13|OwnerPartId=-1|Location.X=729|Location.Y=252|Color=8388608|FontID=1|IsHidden=T|Text=*|Name=SHEETPART
|RECORD=41|OwnerIndex=951|IndexInSheet=14|OwnerPartId=-1|Location.X=729|Location.Y=252|Color=8388608|FontID=1|IsHidden=T|Text=DIO, SCHOTTKY, BAT54S, DUAL SERIES, 30V, 200MA, SC-70|Name=DESC
|RECORD=41|OwnerIndex=951|IndexInSheet=15|OwnerPartId=-1|Location.X=729|Location.Y=252|Color=8388608|FontID=1|IsHidden=T|Text=Digi-Key|Name=Supplier 1|ReadOnlyState=3
|RECORD=41|OwnerIndex=951|IndexInSheet=16|OwnerPartId=-1|Location.X=729|Location.Y=252|Color=8388608|FontID=1|IsHidden=T|Text=BAT54SWQ-7-FDICT-ND|Name=Supplier Part Number 1|ReadOnlyState=3
|RECORD=41|OwnerIndex=951|IndexInSheet=17|OwnerPartId=-1|Location.X=771|Location.Y=205|Color=8388608|FontID=7|Text=BAT54SW|Name=VALUE
|RECORD=2|OwnerIndex=951|OwnerPartId=1|FormalType=1|Electrical=4|PinConglomerate=51|PinLength=20|Location.X=760|Location.Y=200|Name=2|Designator=2|SwapIdPin=1|SwapIDPart=1|PinPropagationDelay=0.000000E+000
|RECORD=2|OwnerIndex=951|OwnerPartId=1|FormalType=1|Electrical=4|PinConglomerate=49|PinLength=20|Location.X=750|Location.Y=230|Name=3|Designator=3|SwapIdPin=2|SwapIDPart=1|PinPropagationDelay=0.000000E+000
|RECORD=2|OwnerIndex=951|OwnerPartId=1|FormalType=1|Electrical=4|PinConglomerate=51|PinLength=20|Location.X=740|Location.Y=200|Name=1|Designator=1|SwapIdPin=3|SwapIDPart=1|PinPropagationDelay=0.000000E+000
|RECORD=13|OwnerIndex=951|IsNotAccesible=T|IndexInSheet=21|OwnerPartId=1|Location.X=740|Location.Y=230|Corner.X=740|Corner.Y=220|LineWidth=1|Color=16711680
|RECORD=13|OwnerIndex=951|IsNotAccesible=T|IndexInSheet=22|OwnerPartId=1|Location.X=750|Location.Y=208|Corner.X=770|Corner.Y=208|LineWidth=1|Color=16711680
|RECORD=13|OwnerIndex=951|IsNotAccesible=T|IndexInSheet=23|OwnerPartId=1|Location.X=760|Location.Y=210|Corner.X=760|Corner.Y=200|LineWidth=1|Color=16711680
|RECORD=13|OwnerIndex=951|IsNotAccesible=T|IndexInSheet=24|OwnerPartId=1|Location.X=760|Location.Y=230|Corner.X=760|Corner.Y=220|LineWidth=1|Color=16711680
|RECORD=13|OwnerIndex=951|IsNotAccesible=T|IndexInSheet=25|OwnerPartId=1|Location.X=740|Location.Y=210|Corner.X=740|Corner.Y=200|LineWidth=1|Color=16711680
|RECORD=13|OwnerIndex=951|IsNotAccesible=T|IndexInSheet=26|OwnerPartId=1|Location.X=730|Location.Y=220|Corner.X=750|Corner.Y=220|LineWidth=1|Color=16711680
|RECORD=7|OwnerIndex=951|IsNotAccesible=T|IndexInSheet=27|OwnerPartId=1|LineWidth=1|Color=16711680|AreaColor=16711680|IsSolid=T|LocationCount=3|X1=740|Y1=220|Y1_Frac=20000|X2=732|X2_Frac=50000|Y2=207|Y2_Frac=70000|X3=747|X3_Frac=50000|Y3=207|Y3_Frac=70000
|RECORD=7|OwnerIndex=951|IsNotAccesible=T|IndexInSheet=28|OwnerPartId=1|LineWidth=1|Color=16711680|AreaColor=16711680|IsSolid=T|LocationCount=3|X1=760|Y1=208|X2=767|X2_Frac=50000|Y2=220|Y2_Frac=50000|X3=752|X3_Frac=50000|Y3=220|Y3_Frac=50000
|RECORD=6|OwnerIndex=951|IsNotAccesible=T|IndexInSheet=29|OwnerPartId=1|LineWidth=1|Color=16711680|LocationCount=2|X1=740|Y1=230|X2=760|Y2=230
|RECORD=41|OwnerIndex=951|IndexInSheet=30|OwnerPartId=-1|Location.X=729|Location.Y=252|Color=8388608|FontID=1|IsHidden=T|Text=<VALENTIUM>|Name=VALENTIUM PART NUM
|RECORD=34|OwnerIndex=951|IndexInSheet=-1|OwnerPartId=-1|Location.X=771|Location.Y=217|Color=8388608|FontID=1|Text=D6|Name=Designator|ReadOnlyState=1
|RECORD=41|OwnerIndex=951|IndexInSheet=-1|OwnerPartId=-1|Location.X=729|Location.Y=252|Color=8388608|FontID=1|IsHidden=T|Text=BAT54SW|Name=Comment
|RECORD=44|OwnerIndex=951
|RECORD=45|OwnerIndex=988|IndexInSheet=-1|Description=SOT323-3 (SC70), 3-Leads, Body 2.00x2.10mm, Pitch 0.65mm, IPC Medium Density|UseComponentLibrary=T|ModelName=SOT65P210X110-3N|ModelType=PCBLIB|DatafileCount=1|ModelDatafileEntity0=SOT65P210X110-3N|ModelDatafileKind0=PCBLib|IsCurrent=T|DatalinksLocked=T|DatabaseDatalinksLocked=T|IntegratedModel=T|DatabaseModel=T
|RECORD=46|OwnerIndex=989
|RECORD=48|OwnerIndex=989
|RECORD=1|LibReference=BAT54SW|ComponentDescription=DIO, SCHOTTKY, BAT54S, DUAL SERIES, 30V, 200MA, SC-70|PartCount=2|DisplayModeCount=1|IndexInSheet=72|OwnerPartId=-1|Location.X=600|Location.Y=180|Orientation=1|CurrentPartId=1|LibraryPath=*|SourceLibraryName=Passives.IntLib|TargetFileName=*|AreaColor=11599871|Color=128|PartIDLocked=F|DesignItemId=BAT54SW|AllPinCount=3
|RECORD=41|OwnerIndex=992|OwnerPartId=-1|Location.X=589|Location.Y=252|Color=8388608|FontID=7|IsHidden=T|Text=BAT54SWQ-7-F|Name=MFG PART NUM
|RECORD=41|OwnerIndex=992|IndexInSheet=1|OwnerPartId=-1|Location.X=589|Location.Y=252|Color=8388608|FontID=7|IsHidden=T|Text=9/4/2013|Name=MODIFY DATE
|RECORD=41|OwnerIndex=992|IndexInSheet=2|OwnerPartId=-1|Location.X=589|Location.Y=252|Color=8388608|FontID=7|IsHidden=T|Text=DIODES INC|Name=MFG NAME
|RECORD=41|OwnerIndex=992|IndexInSheet=3|OwnerPartId=-1|Location.X=589|Location.Y=252|Color=8388608|FontID=7|IsHidden=T|Text=DIO, SCHOTTKY|Name=CATEGORY
|RECORD=41|OwnerIndex=992|IndexInSheet=4|OwnerPartId=-1|Location.X=589|Location.Y=252|Color=8388608|FontID=7|IsHidden=T|Name=DATE
|RECORD=41|OwnerIndex=992|IndexInSheet=5|OwnerPartId=-1|Location.X=589|Location.Y=252|Color=8388608|FontID=7|IsHidden=T|Text=150C|Name=MAXTEMP
|RECORD=41|OwnerIndex=992|IndexInSheet=6|OwnerPartId=-1|Location.X=589|Location.Y=252|Color=8388608|FontID=7|IsHidden=T|Text=-55C|Name=MINTEMP
|RECORD=41|OwnerIndex=992|IndexInSheet=7|OwnerPartId=-1|Location.X=589|Location.Y=252|Color=8388608|FontID=7|IsHidden=T|Text=SERIES|Name=OTHER
|RECORD=41|OwnerIndex=992|IndexInSheet=8|OwnerPartId=-1|Location.X=589|Location.Y=252|Color=8388608|FontID=7|IsHidden=T|Text=SCHOTTKY|Name=P1
|RECORD=41|OwnerIndex=992|IndexInSheet=9|OwnerPartId=-1|Location.X=589|Location.Y=252|Color=8388608|FontID=7|IsHidden=T|Text=30V|Name=P2
|RECORD=41|OwnerIndex=992|IndexInSheet=10|OwnerPartId=-1|Location.X=589|Location.Y=252|Color=8388608|FontID=7|IsHidden=T|Text=200mA,200mW|Name=P3
|RECORD=41|OwnerIndex=992|IndexInSheet=11|OwnerPartId=-1|Location.X=589|Location.Y=252|Color=8388608|FontID=7|IsHidden=T|Text=SC-70|Name=SIZE
|RECORD=41|OwnerIndex=992|IndexInSheet=12|OwnerPartId=-1|Location.X=589|Location.Y=252|Color=8388608|FontID=7|IsHidden=T|Name=SUB
|RECORD=41|OwnerIndex=992|IndexInSheet=13|OwnerPartId=-1|Location.X=589|Location.Y=252|Color=8388608|FontID=1|IsHidden=T|Text=*|Name=SHEETPART
|RECORD=41|OwnerIndex=992|IndexInSheet=14|OwnerPartId=-1|Location.X=589|Location.Y=252|Color=8388608|FontID=1|IsHidden=T|Text=DIO, SCHOTTKY, BAT54S, DUAL SERIES, 30V, 200MA, SC-70|Name=DESC
|RECORD=41|OwnerIndex=992|IndexInSheet=15|OwnerPartId=-1|Location.X=589|Location.Y=252|Color=8388608|FontID=1|IsHidden=T|Text=Digi-Key|Name=Supplier 1|ReadOnlyState=3
|RECORD=41|OwnerIndex=992|IndexInSheet=16|OwnerPartId=-1|Location.X=589|Location.Y=252|Color=8388608|FontID=1|IsHidden=T|Text=BAT54SWQ-7-FDICT-ND|Name=Supplier Part Number 1|ReadOnlyState=3
|RECORD=41|OwnerIndex=992|IndexInSheet=17|OwnerPartId=-1|Location.X=631|Location.Y=205|Color=8388608|FontID=7|Text=BAT54SW|Name=VALUE
|RECORD=2|OwnerIndex=992|OwnerPartId=1|FormalType=1|Electrical=4|PinConglomerate=51|PinLength=20|Location.X=620|Location.Y=200|Name=2|Designator=2|SwapIdPin=1|SwapIDPart=1|PinPropagationDelay=0.000000E+000
|RECORD=2|OwnerIndex=992|OwnerPartId=1|FormalType=1|Electrical=4|PinConglomerate=49|PinLength=20|Location.X=610|Location.Y=230|Name=3|Designator=3|SwapIdPin=2|SwapIDPart=1|PinPropagationDelay=0.000000E+000
|RECORD=2|OwnerIndex=992|OwnerPartId=1|FormalType=1|Electrical=4|PinConglomerate=51|PinLength=20|Location.X=600|Location.Y=200|Name=1|Designator=1|SwapIdPin=3|SwapIDPart=1|PinPropagationDelay=0.000000E+000
|RECORD=13|OwnerIndex=992|IsNotAccesible=T|IndexInSheet=21|OwnerPartId=1|Location.X=600|Location.Y=230|Corner.X=600|Corner.Y=220|LineWidth=1|Color=16711680
|RECORD=13|OwnerIndex=992|IsNotAccesible=T|IndexInSheet=22|OwnerPartId=1|Location.X=610|Location.Y=208|Corner.X=630|Corner.Y=208|LineWidth=1|Color=16711680
|RECORD=13|OwnerIndex=992|IsNotAccesible=T|IndexInSheet=23|OwnerPartId=1|Location.X=620|Location.Y=210|Corner.X=620|Corner.Y=200|LineWidth=1|Color=16711680
|RECORD=13|OwnerIndex=992|IsNotAccesible=T|IndexInSheet=24|OwnerPartId=1|Location.X=620|Location.Y=230|Corner.X=620|Corner.Y=220|LineWidth=1|Color=16711680
|RECORD=13|OwnerIndex=992|IsNotAccesible=T|IndexInSheet=25|OwnerPartId=1|Location.X=600|Location.Y=210|Corner.X=600|Corner.Y=200|LineWidth=1|Color=16711680
|RECORD=13|OwnerIndex=992|IsNotAccesible=T|IndexInSheet=26|OwnerPartId=1|Location.X=590|Location.Y=220|Corner.X=610|Corner.Y=220|LineWidth=1|Color=16711680
|RECORD=7|OwnerIndex=992|IsNotAccesible=T|IndexInSheet=27|OwnerPartId=1|LineWidth=1|Color=16711680|AreaColor=16711680|IsSolid=T|LocationCount=3|X1=600|Y1=220|Y1_Frac=20000|X2=592|X2_Frac=50000|Y2=207|Y2_Frac=70000|X3=607|X3_Frac=50000|Y3=207|Y3_Frac=70000
|RECORD=7|OwnerIndex=992|IsNotAccesible=T|IndexInSheet=28|OwnerPartId=1|LineWidth=1|Color=16711680|AreaColor=16711680|IsSolid=T|LocationCount=3|X1=620|Y1=208|X2=627|X2_Frac=50000|Y2=220|Y2_Frac=50000|X3=612|X3_Frac=50000|Y3=220|Y3_Frac=50000
|RECORD=6|OwnerIndex=992|IsNotAccesible=T|IndexInSheet=29|OwnerPartId=1|LineWidth=1|Color=16711680|LocationCount=2|X1=600|Y1=230|X2=620|Y2=230
|RECORD=41|OwnerIndex=992|IndexInSheet=30|OwnerPartId=-1|Location.X=589|Location.Y=252|Color=8388608|FontID=1|IsHidden=T|Text=<VALENTIUM>|Name=VALENTIUM PART NUM
|RECORD=34|OwnerIndex=992|IndexInSheet=-1|OwnerPartId=-1|Location.X=631|Location.Y=217|Color=8388608|FontID=1|Text=D5|Name=Designator|ReadOnlyState=1
|RECORD=41|OwnerIndex=992|IndexInSheet=-1|OwnerPartId=-1|Location.X=589|Location.Y=252|Color=8388608|FontID=1|IsHidden=T|Text=BAT54SW|Name=Comment
|RECORD=44|OwnerIndex=992
|RECORD=45|OwnerIndex=1029|IndexInSheet=-1|Description=SOT323-3 (SC70), 3-Leads, Body 2.00x2.10mm, Pitch 0.65mm, IPC Medium Density|UseComponentLibrary=T|ModelName=SOT65P210X110-3N|ModelType=PCBLIB|DatafileCount=1|ModelDatafileEntity0=SOT65P210X110-3N|ModelDatafileKind0=PCBLib|IsCurrent=T|DatalinksLocked=T|DatabaseDatalinksLocked=T|IntegratedModel=T|DatabaseModel=T
|RECORD=46|OwnerIndex=1030
|RECORD=48|OwnerIndex=1030
|RECORD=25|IndexInSheet=73|OwnerPartId=-1|Location.X=940|Location.Y=950|Color=128|FontID=1|Text=PRSNT
|RECORD=25|IndexInSheet=74|OwnerPartId=-1|Location.X=600|Location.Y=780|Color=128|FontID=1|Text=PRSNT
|RECORD=25|IndexInSheet=75|OwnerPartId=-1|Location.X=600|Location.Y=640|Color=128|FontID=1|Text=PRSNT
|RECORD=17|IndexInSheet=76|OwnerPartId=-1|ShowNetName=T|Location.X=620|Location.Y=260|Color=255|FontID=1|Text=FPGA_TCK|IsCrossSheetConnector=T
|RECORD=41|OwnerIndex=1036|OwnerPartId=-1|Location.X=681|Location.X_Frac=73633|Location.Y=260|Justification=3|Color=8388608|FontID=1|Text=FPGA[2D], PCIe_JTAG[3C]|Name=CrossRef|ReadOnlyState=3
|RECORD=17|IndexInSheet=77|OwnerPartId=-1|ShowNetName=T|Location.X=760|Location.Y=260|Color=255|FontID=1|Text=FPGA_TDO|IsCrossSheetConnector=T
|RECORD=41|OwnerIndex=1038|OwnerPartId=-1|Location.X=821|Location.X_Frac=81128|Location.Y=260|Justification=3|Color=8388608|FontID=1|Text=FPGA[2D], PCIe_JTAG[3C]|Name=CrossRef|ReadOnlyState=3
|RECORD=17|IndexInSheet=78|OwnerPartId=-1|ShowNetName=T|Location.X=900|Location.Y=260|Color=255|FontID=1|Text=FPGA_TMS|IsCrossSheetConnector=T
|RECORD=41|OwnerIndex=1040|OwnerPartId=-1|Location.X=961|Location.X_Frac=68342|Location.Y=260|Justification=3|Color=8388608|FontID=1|Text=FPGA[3D], PCIe_JTAG[3C]|Name=CrossRef|ReadOnlyState=3
|RECORD=17|IndexInSheet=79|OwnerPartId=-1|ShowNetName=T|Location.X=1040|Location.Y=260|Color=255|FontID=1|Text=FPGA_TDI|IsCrossSheetConnector=T
|RECORD=41|OwnerIndex=1042|OwnerPartId=-1|Location.X=1098|Location.X_Frac=42504|Location.Y=260|Justification=3|Color=8388608|FontID=1|Text=FPGA[3D], PCIe_JTAG[3C]|Name=CrossRef|ReadOnlyState=3
|RECORD=27|IndexInSheet=80|OwnerPartId=-1|LineWidth=1|Color=8388608|LocationCount=2|X1=740|Y1=690|X2=740|Y2=700
|RECORD=27|IndexInSheet=81|OwnerPartId=-1|LineWidth=1|Color=8388608|LocationCount=2|X1=760|Y1=670|X2=540|Y2=670
|RECORD=27|IndexInSheet=82|OwnerPartId=-1|LineWidth=1|Color=8388608|LocationCount=2|X1=760|Y1=680|X2=540|Y2=680
|RECORD=27|IndexInSheet=83|OwnerPartId=-1|LineWidth=1|Color=8388608|LocationCount=2|X1=760|Y1=710|X2=540|Y2=710
|RECORD=27|IndexInSheet=84|OwnerPartId=-1|LineWidth=1|Color=8388608|LocationCount=2|X1=760|Y1=720|X2=540|Y2=720
|RECORD=27|IndexInSheet=85|OwnerPartId=-1|LineWidth=1|Color=8388608|LocationCount=2|X1=760|Y1=750|X2=540|Y2=750
|RECORD=27|IndexInSheet=86|OwnerPartId=-1|LineWidth=1|Color=8388608|LocationCount=2|X1=760|Y1=760|X2=540|Y2=760
|RECORD=27|IndexInSheet=87|OwnerPartId=-1|LineWidth=1|Color=8388608|LocationCount=2|X1=760|Y1=800|X2=540|Y2=800
|RECORD=27|IndexInSheet=88|OwnerPartId=-1|LineWidth=1|Color=8388608|LocationCount=2|X1=760|Y1=810|X2=540|Y2=810
|RECORD=27|IndexInSheet=89|OwnerPartId=-1|LineWidth=1|Color=8388608|LocationCount=3|X1=760|Y1=880|X2=540|Y2=880|X3=540|Y3=970
|RECORD=27|IndexInSheet=90|OwnerPartId=-1|LineWidth=1|Color=8388608|LocationCount=2|X1=600|Y1=180|X2=590|Y2=180
|RECORD=27|IndexInSheet=91|OwnerPartId=-1|LineWidth=1|Color=8388608|LocationCount=2|X1=670|Y1=640|X2=590|Y2=640
|RECORD=27|IndexInSheet=92|OwnerPartId=-1|LineWidth=1|Color=8388608|LocationCount=2|X1=670|Y1=780|X2=590|Y2=780
|RECORD=27|IndexInSheet=93|OwnerPartId=-1|LineWidth=1|Color=8388608|LocationCount=3|X1=610|Y1=250|X2=610|Y2=260|X3=620|Y3=260
|RECORD=27|IndexInSheet=94|OwnerPartId=-1|LineWidth=1|Color=8388608|LocationCount=3|X1=630|Y1=170|X2=630|Y2=180|X3=620|Y3=180
|RECORD=27|IndexInSheet=95|OwnerPartId=-1|LineWidth=1|Color=8388608|LocationCount=5|X1=760|Y1=930|X2=670|Y2=930|X3=670|Y3=940|X4=670|Y4=950|X5=670|Y5=970
|RECORD=27|IndexInSheet=96|OwnerPartId=-1|LineWidth=1|Color=8388608|LocationCount=2|X1=760|Y1=940|X2=670|Y2=940
|RECORD=27|IndexInSheet=97|OwnerPartId=-1|LineWidth=1|Color=8388608|LocationCount=2|X1=760|Y1=950|X2=670|Y2=950
|RECORD=27|IndexInSheet=98|OwnerPartId=-1|LineWidth=1|Color=8388608|LocationCount=2|X1=760|Y1=640|X2=720|Y2=640
|RECORD=27|IndexInSheet=99|OwnerPartId=-1|LineWidth=1|Color=8388608|LocationCount=2|X1=760|Y1=780|X2=720|Y2=780
|RECORD=27|IndexInSheet=100|OwnerPartId=-1|LineWidth=1|Color=8388608|LocationCount=2|X1=740|Y1=180|X2=730|Y2=180
|RECORD=27|IndexInSheet=101|OwnerPartId=-1|LineWidth=1|Color=8388608|LocationCount=2|X1=790|Y1=340|X2=730|Y2=340
|RECORD=27|IndexInSheet=102|OwnerPartId=-1|LineWidth=1|Color=8388608|LocationCount=2|X1=790|Y1=370|X2=730|Y2=370
|RECORD=27|IndexInSheet=103|OwnerPartId=-1|LineWidth=1|Color=8388608|LocationCount=2|X1=790|Y1=400|X2=730|Y2=400
|RECORD=27|IndexInSheet=104|OwnerPartId=-1|LineWidth=1|Color=8388608|LocationCount=2|X1=790|Y1=430|X2=730|Y2=430
|RECORD=27|IndexInSheet=105|OwnerPartId=-1|LineWidth=1|Color=8388608|LocationCount=2|X1=760|Y1=630|X2=740|Y2=630
|RECORD=27|IndexInSheet=106|OwnerPartId=-1|LineWidth=1|Color=8388608|LocationCount=2|X1=760|Y1=660|X2=740|Y2=660
|RECORD=27|IndexInSheet=107|OwnerPartId=-1|LineWidth=1|Color=8388608|LocationCount=5|X1=760|Y1=690|X2=740|Y2=690|X3=740|Y3=660|X4=740|Y4=630|X5=740|Y5=600
|RECORD=27|IndexInSheet=108|OwnerPartId=-1|LineWidth=1|Color=8388608|LocationCount=2|X1=760|Y1=700|X2=740|Y2=700
|RECORD=27|IndexInSheet=109|OwnerPartId=-1|LineWidth=1|Color=8388608|LocationCount=2|X1=760|Y1=730|X2=740|Y2=730
|RECORD=27|IndexInSheet=110|OwnerPartId=-1|LineWidth=1|Color=8388608|LocationCount=2|X1=760|Y1=740|X2=740|Y2=740
|RECORD=27|IndexInSheet=111|OwnerPartId=-1|LineWidth=1|Color=8388608|LocationCount=2|X1=760|Y1=770|X2=740|Y2=770
|RECORD=27|IndexInSheet=112|OwnerPartId=-1|LineWidth=1|Color=8388608|LocationCount=2|X1=760|Y1=790|X2=740|Y2=790
|RECORD=27|IndexInSheet=113|OwnerPartId=-1|LineWidth=1|Color=8388608|LocationCount=2|X1=760|Y1=820|X2=740|Y2=820
|RECORD=27|IndexInSheet=114|OwnerPartId=-1|LineWidth=1|Color=8388608|LocationCount=2|X1=760|Y1=890|X2=740|Y2=890
|RECORD=27|IndexInSheet=115|OwnerPartId=-1|LineWidth=1|Color=8388608|LocationCount=9|X1=760|Y1=920|X2=740|Y2=920|X3=740|Y3=890|X4=740|Y4=820|X5=740|Y5=790|X6=740|Y6=770|X7=740|Y7=740|X8=740|Y8=730|X9=740|Y9=700
|RECORD=27|IndexInSheet=116|OwnerPartId=-1|LineWidth=1|Color=8388608|LocationCount=3|X1=750|Y1=250|X2=750|Y2=260|X3=760|Y3=260
|RECORD=27|IndexInSheet=117|OwnerPartId=-1|LineWidth=1|Color=8388608|LocationCount=4|X1=760|Y1=180|X2=760|Y2=179|X3=770|Y3=179|X4=770|Y4=169
|RECORD=27|IndexInSheet=118|OwnerPartId=-1|LineWidth=1|Color=8388608|LocationCount=4|X1=880|Y1=350|X2=870|Y2=350|X3=870|Y3=340|X4=840|Y4=340
|RECORD=27|IndexInSheet=119|OwnerPartId=-1|LineWidth=1|Color=8388608|LocationCount=2|X1=880|Y1=370|X2=840|Y2=370
|RECORD=27|IndexInSheet=120|OwnerPartId=-1|LineWidth=1|Color=8388608|LocationCount=4|X1=880|Y1=380|X2=870|Y2=380|X3=870|Y3=400|X4=840|Y4=400
|RECORD=27|IndexInSheet=121|OwnerPartId=-1|LineWidth=1|Color=8388608|LocationCount=3|X1=880|Y1=390|X2=880|Y2=430|X3=840|Y3=430
|RECORD=27|IndexInSheet=122|OwnerPartId=-1|LineWidth=1|Color=8388608|LocationCount=2|X1=880|Y1=180|X2=870|Y2=180
|RECORD=27|IndexInSheet=123|OwnerPartId=-1|LineWidth=1|Color=8388608|LocationCount=3|X1=890|Y1=250|X2=890|Y2=260|X3=900|Y3=260
|RECORD=27|IndexInSheet=124|OwnerPartId=-1|LineWidth=1|Color=8388608|LocationCount=3|X1=910|Y1=170|X2=910|Y2=180|X3=900|Y3=180
|RECORD=27|IndexInSheet=125|OwnerPartId=-1|LineWidth=1|Color=8388608|LocationCount=2|X1=920|Y1=640|X2=940|Y2=640
|RECORD=27|IndexInSheet=126|OwnerPartId=-1|LineWidth=1|Color=8388608|LocationCount=2|X1=920|Y1=650|X2=1080|Y2=650
|RECORD=27|IndexInSheet=127|OwnerPartId=-1|LineWidth=1|Color=8388608|LocationCount=2|X1=920|Y1=660|X2=1040|Y2=660
|RECORD=27|IndexInSheet=128|OwnerPartId=-1|LineWidth=1|Color=8388608|LocationCount=2|X1=920|Y1=670|X2=940|Y2=670
|RECORD=27|IndexInSheet=129|OwnerPartId=-1|LineWidth=1|Color=8388608|LocationCount=2|X1=920|Y1=680|X2=940|Y2=680
|RECORD=27|IndexInSheet=130|OwnerPartId=-1|LineWidth=1|Color=8388608|LocationCount=2|X1=920|Y1=690|X2=1080|Y2=690
|RECORD=27|IndexInSheet=131|OwnerPartId=-1|LineWidth=1|Color=8388608|LocationCount=2|X1=920|Y1=700|X2=1040|Y2=700
|RECORD=27|IndexInSheet=132|OwnerPartId=-1|LineWidth=1|Color=8388608|LocationCount=2|X1=920|Y1=710|X2=940|Y2=710
|RECORD=27|IndexInSheet=133|OwnerPartId=-1|LineWidth=1|Color=8388608|LocationCount=2|X1=920|Y1=720|X2=940|Y2=720
|RECORD=27|IndexInSheet=134|OwnerPartId=-1|LineWidth=1|Color=8388608|LocationCount=2|X1=920|Y1=730|X2=1080|Y2=730
|RECORD=27|IndexInSheet=135|OwnerPartId=-1|LineWidth=1|Color=8388608|LocationCount=2|X1=920|Y1=740|X2=1040|Y2=740
|RECORD=27|IndexInSheet=136|OwnerPartId=-1|LineWidth=1|Color=8388608|LocationCount=2|X1=920|Y1=750|X2=940|Y2=750
|RECORD=27|IndexInSheet=137|OwnerPartId=-1|LineWidth=1|Color=8388608|LocationCount=2|X1=920|Y1=770|X2=940|Y2=770
|RECORD=27|IndexInSheet=138|OwnerPartId=-1|LineWidth=1|Color=8388608|LocationCount=2|X1=920|Y1=780|X2=1080|Y2=780
|RECORD=27|IndexInSheet=139|OwnerPartId=-1|LineWidth=1|Color=8388608|LocationCount=2|X1=920|Y1=790|X2=1010|Y2=790
|RECORD=27|IndexInSheet=140|OwnerPartId=-1|LineWidth=1|Color=8388608|LocationCount=2|X1=920|Y1=800|X2=940|Y2=800
|RECORD=27|IndexInSheet=141|OwnerPartId=-1|LineWidth=1|Color=8388608|LocationCount=2|X1=920|Y1=810|X2=1080|Y2=810
|RECORD=27|IndexInSheet=142|OwnerPartId=-1|LineWidth=1|Color=8388608|LocationCount=2|X1=920|Y1=820|X2=1040|Y2=820
|RECORD=27|IndexInSheet=143|OwnerPartId=-1|LineWidth=1|Color=8388608|LocationCount=2|X1=920|Y1=830|X2=940|Y2=830
|RECORD=27|IndexInSheet=144|OwnerPartId=-1|LineWidth=1|Color=8388608|LocationCount=3|X1=920|Y1=850|X2=1060|Y2=850|X3=1060|Y3=860
|RECORD=27|IndexInSheet=145|OwnerPartId=-1|LineWidth=1|Color=8388608|LocationCount=3|X1=920|Y1=860|X2=1030|Y2=860|X3=1030|Y3=870
|RECORD=27|IndexInSheet=146|OwnerPartId=-1|LineWidth=1|Color=8388608|LocationCount=3|X1=920|Y1=870|X2=1030|Y2=870|X3=1030|Y3=940
|RECORD=27|IndexInSheet=147|OwnerPartId=-1|LineWidth=1|Color=8388608|LocationCount=12|X1=920|Y1=920|X2=940|Y2=920|X3=940|Y3=830|X4=940|Y4=800|X5=940|Y5=770|X6=940|Y6=750|X7=940|Y7=720|X8=940|Y8=710|X9=940|Y9=680|X10=940|Y10=670|X11=940|Y11=640|X12=940|Y12=600
|RECORD=27|IndexInSheet=148|OwnerPartId=-1|LineWidth=1|Color=8388608|LocationCount=3|X1=920|Y1=930|X2=990|Y2=930|X3=990|Y3=940
|RECORD=27|IndexInSheet=149|OwnerPartId=-1|LineWidth=1|Color=8388608|LocationCount=3|X1=920|Y1=940|X2=990|Y2=940|X3=990|Y3=970
|RECORD=27|IndexInSheet=150|OwnerPartId=-1|LineWidth=1|Color=8388608|LocationCount=2|X1=920|Y1=950|X2=980|Y2=950
|RECORD=27|IndexInSheet=151|OwnerPartId=-1|LineWidth=1|Color=8388608|LocationCount=2|X1=980|Y1=350|X2=1010|Y2=350
|RECORD=27|IndexInSheet=152|OwnerPartId=-1|LineWidth=1|Color=8388608|LocationCount=4|X1=980|Y1=370|X2=1030|Y2=370|X3=1030|Y3=380|X4=1030|Y4=410
|RECORD=27|IndexInSheet=153|OwnerPartId=-1|LineWidth=1|Color=8388608|LocationCount=2|X1=980|Y1=380|X2=1030|Y2=380
|RECORD=27|IndexInSheet=154|OwnerPartId=-1|LineWidth=1|Color=8388608|LocationCount=4|X1=980|Y1=390|X2=1010|Y2=390|X3=1010|Y3=350|X4=1010|Y4=330
|RECORD=27|IndexInSheet=155|OwnerPartId=-1|LineWidth=1|Color=8388608|LocationCount=2|X1=1010|Y1=180|X2=1020|Y2=180
|RECORD=27|IndexInSheet=156|OwnerPartId=-1|LineWidth=1|Color=8388608|LocationCount=3|X1=1030|Y1=250|X2=1030|Y2=260|X3=1040|Y3=260
|RECORD=27|IndexInSheet=157|OwnerPartId=-1|LineWidth=1|Color=8388608|LocationCount=3|X1=1040|Y1=180|X2=1050|Y2=180|X3=1050|Y3=170
|RECORD=27|IndexInSheet=158|OwnerPartId=-1|LineWidth=1|Color=8388608|LocationCount=2|X1=1040|Y1=790|X2=1190|Y2=790
|RECORD=27|IndexInSheet=159|OwnerPartId=-1|LineWidth=1|Color=8388608|LocationCount=2|X1=1060|Y1=850|X2=1190|Y2=850
|RECORD=27|IndexInSheet=160|OwnerPartId=-1|LineWidth=1|Color=8388608|LocationCount=2|X1=1070|Y1=660|X2=1190|Y2=660
|RECORD=27|IndexInSheet=161|OwnerPartId=-1|LineWidth=1|Color=8388608|LocationCount=2|X1=1070|Y1=700|X2=1190|Y2=700
|RECORD=27|IndexInSheet=162|OwnerPartId=-1|LineWidth=1|Color=8388608|LocationCount=2|X1=1070|Y1=740|X2=1190|Y2=740
|RECORD=27|IndexInSheet=163|OwnerPartId=-1|LineWidth=1|Color=8388608|LocationCount=2|X1=1070|Y1=820|X2=1190|Y2=820
|RECORD=27|IndexInSheet=164|OwnerPartId=-1|LineWidth=1|Color=8388608|LocationCount=2|X1=1110|Y1=650|X2=1190|Y2=650
|RECORD=27|IndexInSheet=165|OwnerPartId=-1|LineWidth=1|Color=8388608|LocationCount=2|X1=1110|Y1=690|X2=1190|Y2=690
|RECORD=27|IndexInSheet=166|OwnerPartId=-1|LineWidth=1|Color=8388608|LocationCount=2|X1=1110|Y1=730|X2=1190|Y2=730
|RECORD=27|IndexInSheet=167|OwnerPartId=-1|LineWidth=1|Color=8388608|LocationCount=2|X1=1110|Y1=780|X2=1190|Y2=780
|RECORD=27|IndexInSheet=168|OwnerPartId=-1|LineWidth=1|Color=8388608|LocationCount=2|X1=1110|Y1=810|X2=1190|Y2=810
|RECORD=27|IndexInSheet=169|OwnerPartId=-1|LineWidth=1|Color=8388608|LocationCount=2|X1=1060|Y1=910|X2=1060|Y2=920
|RECORD=41|IndexInSheet=170|OwnerPartId=-1|Color=8388608|FontID=1|IsHidden=T|Name=ConfigurationParameters|ReadOnlyState=1
|RECORD=41|IndexInSheet=171|OwnerPartId=-1|Color=8388608|FontID=1|IsHidden=T|Name=ConfiguratorName|ReadOnlyState=1
|RECORD=41|IndexInSheet=172|OwnerPartId=-1|Color=8388608|FontID=1|IsHidden=T|Name=VersionControl_RevNumber|ReadOnlyState=1
|RECORD=41|IndexInSheet=173|OwnerPartId=-1|Color=8388608|FontID=1|IsHidden=T|Name=IsUserConfigurable|ReadOnlyState=1
|RECORD=41|IndexInSheet=174|OwnerPartId=-1|Color=8388608|FontID=1|IsHidden=T|Name=VersionControl_ProjFolderRevNumber|ReadOnlyState=1
|RECORD=41|IndexInSheet=175|OwnerPartId=-1|Color=8388608|FontID=1|IsHidden=T|Name=SPICEModelCache|ReadOnlyState=1
|RECORD=41|IndexInSheet=176|OwnerPartId=-1|Color=8388608|FontID=1|IsHidden=T|Text=*|Name=CurrentTime|ReadOnlyState=1
|RECORD=41|IndexInSheet=177|OwnerPartId=-1|Color=8388608|FontID=1|IsHidden=T|Text=*|Name=CurrentDate|ReadOnlyState=1
|RECORD=41|IndexInSheet=178|OwnerPartId=-1|Color=8388608|FontID=1|IsHidden=T|Text=*|Name=Time|ReadOnlyState=1
|RECORD=41|IndexInSheet=179|OwnerPartId=-1|Color=8388608|FontID=1|IsHidden=T|Text=*|Name=Date|ReadOnlyState=1
|RECORD=41|IndexInSheet=180|OwnerPartId=-1|Color=8388608|FontID=1|IsHidden=T|Text=*|Name=DocumentFullPathAndName|ReadOnlyState=1
|RECORD=41|IndexInSheet=181|OwnerPartId=-1|Color=8388608|FontID=1|IsHidden=T|Text=*|Name=DocumentName|ReadOnlyState=1
|RECORD=41|IndexInSheet=182|OwnerPartId=-1|Color=8388608|FontID=1|IsHidden=T|Text=*|Name=ModifiedDate|ReadOnlyState=1
|RECORD=41|IndexInSheet=183|OwnerPartId=-1|Color=8388608|FontID=1|IsHidden=T|Text=*|Name=ApprovedBy|ReadOnlyState=1
|RECORD=41|IndexInSheet=184|OwnerPartId=-1|Color=8388608|FontID=1|IsHidden=T|Text=*|Name=CheckedBy|ReadOnlyState=1
|RECORD=41|IndexInSheet=185|OwnerPartId=-1|Color=8388608|FontID=1|IsHidden=T|Text=*|Name=Author|ReadOnlyState=1
|RECORD=41|IndexInSheet=186|OwnerPartId=-1|Color=8388608|FontID=1|IsHidden=T|Text=*|Name=CompanyName|ReadOnlyState=1
|RECORD=41|IndexInSheet=187|OwnerPartId=-1|Color=8388608|FontID=1|IsHidden=T|Text=*|Name=DrawnBy|ReadOnlyState=1
|RECORD=41|IndexInSheet=188|OwnerPartId=-1|Color=8388608|FontID=1|IsHidden=T|Text=*|Name=Engineer|ReadOnlyState=1
|RECORD=41|IndexInSheet=189|OwnerPartId=-1|Color=8388608|FontID=1|IsHidden=T|Text=*|Name=Organization|ReadOnlyState=1
|RECORD=41|IndexInSheet=190|OwnerPartId=-1|Color=8388608|FontID=1|IsHidden=T|Text=*|Name=Address1|ReadOnlyState=1
|RECORD=41|IndexInSheet=191|OwnerPartId=-1|Color=8388608|FontID=1|IsHidden=T|Text=*|Name=Address2|ReadOnlyState=1
|RECORD=41|IndexInSheet=192|OwnerPartId=-1|Color=8388608|FontID=1|IsHidden=T|Text=*|Name=Address3|ReadOnlyState=1
|RECORD=41|IndexInSheet=193|OwnerPartId=-1|Color=8388608|FontID=1|IsHidden=T|Text=*|Name=Address4|ReadOnlyState=1
|RECORD=41|IndexInSheet=194|OwnerPartId=-1|Color=8388608|FontID=1|IsHidden=T|Text=*|Name=Title|ReadOnlyState=1
|RECORD=41|IndexInSheet=195|OwnerPartId=-1|Color=8388608|FontID=1|IsHidden=T|Text=*|Name=DocumentNumber|ReadOnlyState=1
|RECORD=41|IndexInSheet=196|OwnerPartId=-1|Color=8388608|FontID=1|IsHidden=T|Text=*|Name=Revision|ReadOnlyState=1
|RECORD=41|IndexInSheet=197|OwnerPartId=-1|Color=8388608|FontID=1|IsHidden=T|Text=*|Name=SheetNumber|ReadOnlyState=1
|RECORD=41|IndexInSheet=198|OwnerPartId=-1|Color=8388608|FontID=1|IsHidden=T|Text=*|Name=SheetTotal|ReadOnlyState=1
|RECORD=41|IndexInSheet=199|OwnerPartId=-1|Color=8388608|FontID=1|IsHidden=T|Text=*|Name=Rule|ReadOnlyState=1
|RECORD=41|IndexInSheet=200|OwnerPartId=-1|Color=8388608|FontID=1|IsHidden=T|Text=*|Name=ImagePath|ReadOnlyState=1
|RECORD=41|IndexInSheet=201|OwnerPartId=-1|Color=8388608|FontID=1|IsHidden=T|Text=*|Name=ProjectName|ReadOnlyState=1
|RECORD=41|IndexInSheet=202|OwnerPartId=-1|Color=8388608|FontID=1|IsHidden=T|Text=*|Name=Application_BuildNumber|ReadOnlyState=1
|RECORD=29|IndexInSheet=-1|OwnerPartId=-1|Location.X=670|Location.Y=940|Color=128
|RECORD=29|IndexInSheet=-1|OwnerPartId=-1|Location.X=670|Location.Y=950|Color=128
|RECORD=29|IndexInSheet=-1|OwnerPartId=-1|Location.X=740|Location.Y=630|Color=128
|RECORD=29|IndexInSheet=-1|OwnerPartId=-1|Location.X=740|Location.Y=660|Color=128
|RECORD=29|IndexInSheet=-1|OwnerPartId=-1|Location.X=740|Location.Y=690|Color=128
|RECORD=29|IndexInSheet=-1|OwnerPartId=-1|Location.X=740|Location.Y=700|Color=128
|RECORD=29|IndexInSheet=-1|OwnerPartId=-1|Location.X=740|Location.Y=730|Color=128
|RECORD=29|IndexInSheet=-1|OwnerPartId=-1|Location.X=740|Location.Y=740|Color=128
|RECORD=29|IndexInSheet=-1|OwnerPartId=-1|Location.X=740|Location.Y=770|Color=128
|RECORD=29|IndexInSheet=-1|OwnerPartId=-1|Location.X=740|Location.Y=790|Color=128
|RECORD=29|IndexInSheet=-1|OwnerPartId=-1|Location.X=740|Location.Y=820|Color=128
|RECORD=29|IndexInSheet=-1|OwnerPartId=-1|Location.X=740|Location.Y=890|Color=128
|RECORD=29|IndexInSheet=-1|OwnerPartId=-1|Location.X=940|Location.Y=640|Color=128
|RECORD=29|IndexInSheet=-1|OwnerPartId=-1|Location.X=940|Location.Y=670|Color=128
|RECORD=29|IndexInSheet=-1|OwnerPartId=-1|Location.X=940|Location.Y=680|Color=128
|RECORD=29|IndexInSheet=-1|OwnerPartId=-1|Location.X=940|Location.Y=710|Color=128
|RECORD=29|IndexInSheet=-1|OwnerPartId=-1|Location.X=940|Location.Y=720|Color=128
|RECORD=29|IndexInSheet=-1|OwnerPartId=-1|Location.X=940|Location.Y=750|Color=128
|RECORD=29|IndexInSheet=-1|OwnerPartId=-1|Location.X=940|Location.Y=770|Color=128
|RECORD=29|IndexInSheet=-1|OwnerPartId=-1|Location.X=940|Location.Y=800|Color=128
|RECORD=29|IndexInSheet=-1|OwnerPartId=-1|Location.X=940|Location.Y=830|Color=128
|RECORD=29|IndexInSheet=-1|OwnerPartId=-1|Location.X=990|Location.Y=940|Color=128
|RECORD=29|IndexInSheet=-1|OwnerPartId=-1|Location.X=1010|Location.Y=350|Color=128
|RECORD=29|IndexInSheet=-1|OwnerPartId=-1|Location.X=1030|Location.Y=380|Color=128
|RECORD=29|IndexInSheet=-1|OwnerPartId=-1|Location.X=1030|Location.Y=870|Color=128
|RECORD=29|IndexInSheet=-1|OwnerPartId=-1|Location.X=1060|Location.Y=850|Color=128